FILE_TYPE = LIBRARY_PARTS;
{ Packager-XL run on 05-Sep-2022 AT 15:23:30 }
primitive '24LC16BT_I_ST_TSSOP8-G221-1017A';
  pin
    'A0':
      PIN_NUMBER='(1,0)';
      OUTPUT_TYPE='(TS,TS)';
      BIDIRECTIONAL='TRUE';
      INPUT_LOAD='(-0.01,0.01)';
      OUTPUT_LOAD='(1.0,-1.0)';
      PINUSE='BI';
    'A1':
      PIN_NUMBER='(2,0)';
      OUTPUT_TYPE='(TS,TS)';
      BIDIRECTIONAL='TRUE';
      INPUT_LOAD='(-0.01,0.01)';
      OUTPUT_LOAD='(1.0,-1.0)';
      PINUSE='BI';
    'A2':
      PIN_NUMBER='(3,0)';
      OUTPUT_TYPE='(TS,TS)';
      BIDIRECTIONAL='TRUE';
      INPUT_LOAD='(-0.01,0.01)';
      OUTPUT_LOAD='(1.0,-1.0)';
      PINUSE='BI';
    'WP':
      PIN_NUMBER='(7,0)';
      INPUT_LOAD='(-0.01,0.01)';
      PINUSE='IN';
    'SCL':
      PIN_NUMBER='(6,0)';
      INPUT_LOAD='(-0.01,0.01)';
      PINUSE='IN';
    'SDA':
      PIN_NUMBER='(5,0)';
      OUTPUT_TYPE='(TS,TS)';
      BIDIRECTIONAL='TRUE';
      INPUT_LOAD='(-0.01,0.01)';
      OUTPUT_LOAD='(1.0,-1.0)';
      PINUSE='BI';
    'VSS':
      PIN_NUMBER='(0,4)';
      PINUSE='GROUND';
      NO_LOAD_CHECK='Both';
      NO_IO_CHECK='Both';
      NO_ASSERT_CHECK='TRUE';
      NO_DIR_CHECK='TRUE';
      ALLOW_CONNECT='TRUE';
    'VCC':
      PIN_NUMBER='(0,8)';
      PINUSE='POWER';
      NO_LOAD_CHECK='Both';
      NO_IO_CHECK='Both';
      NO_ASSERT_CHECK='TRUE';
      NO_DIR_CHECK='TRUE';
      ALLOW_CONNECT='TRUE';
  end_pin;
  body
      PART_NAME='24LC16BT_I_ST_TSSOP8';
      BODY_NAME='24LC16BT_I_ST_TSSOP8';
      PHYS_DES_PREFIX='U';
      CLASS='IC';
      JEDEC_TYPE='SOP8_173X118_P0256';
      ALT_SYMBOLS='(SOP8_173X118_P0256)';
      DESCRIPTION='IC,24LC64T-I/ST,64KBITS,I2C EEPROM,2.5V-5.5V,-40C TO +85C,TSS~
OP8,ROHS';
      PARENT_PART_TYPE='24LC16BT_I_ST_TSSOP8';
      PARENT_PPT='24LC16BT_I_ST_TSSOP8';
      PARENT_PPT_PART='24LC16BT_I_ST_TSSOP8-G221-10176-01';
  end_body;
end_primitive;
primitive '74HCT2G125DP_TSSOP8-G220-00055A';
  pin
    '1OE*':
      PIN_NUMBER='(1)';
      OUTPUT_TYPE='(TS,TS)';
      BIDIRECTIONAL='TRUE';
      INPUT_LOAD='(-0.01,0.01)';
      OUTPUT_LOAD='(1.0,-1.0)';
      PINUSE='BI';
    '1A':
      PIN_NUMBER='(2)';
      INPUT_LOAD='(-0.01,0.01)';
      PINUSE='IN';
    '2Y':
      PIN_NUMBER='(3)';
      OUTPUT_LOAD='(1.0,-1.0)';
      PINUSE='OUT';
    'GND':
      PIN_NUMBER='(4)';
      PINUSE='GROUND';
      NO_LOAD_CHECK='Both';
      NO_IO_CHECK='Both';
      NO_ASSERT_CHECK='TRUE';
      NO_DIR_CHECK='TRUE';
      ALLOW_CONNECT='TRUE';
    '2A':
      PIN_NUMBER='(5)';
      INPUT_LOAD='(-0.01,0.01)';
      PINUSE='IN';
    '1Y':
      PIN_NUMBER='(6)';
      OUTPUT_LOAD='(1.0,-1.0)';
      PINUSE='OUT';
    '2OE*':
      PIN_NUMBER='(7)';
      OUTPUT_TYPE='(TS,TS)';
      BIDIRECTIONAL='TRUE';
      INPUT_LOAD='(-0.01,0.01)';
      OUTPUT_LOAD='(1.0,-1.0)';
      PINUSE='BI';
    'VCC':
      PIN_NUMBER='(8)';
      PINUSE='POWER';
      NO_LOAD_CHECK='Both';
      NO_IO_CHECK='Both';
      NO_ASSERT_CHECK='TRUE';
      NO_DIR_CHECK='TRUE';
      ALLOW_CONNECT='TRUE';
  end_pin;
  body
      PART_NAME='74HCT2G125DP_TSSOP8';
      BODY_NAME='74HCT2G125DP_TSSOP8';
      PHYS_DES_PREFIX='U';
      CLASS='IC';
      JEDEC_TYPE='SOP8_091_P0197_H035';
      ALT_SYMBOLS='(SOP8_091_P0197_H035)';
      DESCRIPTION='IC,NC7WV125,BUFFER,3_STATE,SMT-8';
      CPN_STATUS='';
      PARENT_PART_TYPE='74HCT2G125DP_TSSOP8';
      PARENT_PPT='74HCT2G125DP_TSSOP8';
      PARENT_PPT_PART='74HCT2G125DP_TSSOP8-G220-00055-01';
  end_body;
end_primitive;
primitive '74LVC1G07_SC70_5-G220-10017-01';
  pin
    'A':
      PIN_NUMBER='(2,0)';
      INPUT_LOAD='(-0.01,0.01)';
      PINUSE='IN';
    'NC':
      PIN_NUMBER='(1,0)';
      PINUSE='NC';
      NO_LOAD_CHECK='Both';
      NO_IO_CHECK='Both';
      NO_ASSERT_CHECK='TRUE';
      NO_DIR_CHECK='TRUE';
      ALLOW_CONNECT='TRUE';
    'Y':
      PIN_NUMBER='(4,0)';
      OUTPUT_LOAD='(1.0,-1.0)';
      PINUSE='OUT';
    'GND':
      PIN_NUMBER='(0,3)';
      PINUSE='GROUND';
      NO_LOAD_CHECK='Both';
      NO_IO_CHECK='Both';
      NO_ASSERT_CHECK='TRUE';
      NO_DIR_CHECK='TRUE';
      ALLOW_CONNECT='TRUE';
    'VCC':
      PIN_NUMBER='(0,5)';
      PINUSE='POWER';
      NO_LOAD_CHECK='Both';
      NO_IO_CHECK='Both';
      NO_ASSERT_CHECK='TRUE';
      NO_DIR_CHECK='TRUE';
      ALLOW_CONNECT='TRUE';
  end_pin;
  body
      PART_NAME='74LVC1G07_SC70_5';
      BODY_NAME='74LVC1G07_SC70_5';
      PHYS_DES_PREFIX='U';
      CLASS='IC';
      JEDEC_TYPE='SC70_5V1';
      ALT_SYMBOLS='(SC70_5V1)';
      DESCRIPTION='IC,74LVC1G07,SINGLE BUFF/DRIVER WITH OD OUTPUT,SC70_5';
      CPN_STATUS='';
      PARENT_PART_TYPE='74LVC1G07_SC70_5';
      PARENT_PPT='74LVC1G07_SC70_5';
      PARENT_PPT_PART='74LVC1G07_SC70_5-G220-10017-01';
  end_body;
end_primitive;
primitive 'AT24MAC402_SOT23_5-A221-00002-A';
  pin
    'SCL':
      PIN_NUMBER='(1)';
      OUTPUT_TYPE='(TS,TS)';
      BIDIRECTIONAL='TRUE';
      INPUT_LOAD='(-0.01,0.01)';
      OUTPUT_LOAD='(1.0,-1.0)';
      PINUSE='BI';
    'GND':
      PIN_NUMBER='(2)';
      PINUSE='GROUND';
      NO_LOAD_CHECK='Both';
      NO_IO_CHECK='Both';
      NO_ASSERT_CHECK='TRUE';
      NO_DIR_CHECK='TRUE';
      ALLOW_CONNECT='TRUE';
    'SDA':
      PIN_NUMBER='(3)';
      OUTPUT_TYPE='(TS,TS)';
      BIDIRECTIONAL='TRUE';
      INPUT_LOAD='(-0.01,0.01)';
      OUTPUT_LOAD='(1.0,-1.0)';
      PINUSE='BI';
    'VCC':
      PIN_NUMBER='(4)';
      PINUSE='POWER';
      NO_LOAD_CHECK='Both';
      NO_IO_CHECK='Both';
      NO_ASSERT_CHECK='TRUE';
      NO_DIR_CHECK='TRUE';
      ALLOW_CONNECT='TRUE';
    'WP':
      PIN_NUMBER='(5)';
      OUTPUT_TYPE='(TS,TS)';
      BIDIRECTIONAL='TRUE';
      INPUT_LOAD='(-0.01,0.01)';
      OUTPUT_LOAD='(1.0,-1.0)';
      PINUSE='BI';
  end_pin;
  body
      PART_NAME='AT24MAC402_SOT23_5';
      BODY_NAME='AT24MAC402_SOT23_5';
      PHYS_DES_PREFIX='U';
      CLASS='IC';
      JEDEC_TYPE='SOT23_5_H039';
      ALT_SYMBOLS='(SOT23_5_H039)';
      DESCRIPTION='IC,I2C,EEPROM,2KBIT WITH FACTORY-PROGRAMMED EUI-64 ADDRESS,1.~
7-5.5V,SOT23-5,SMT,-40C TO 85C';
      CPN_STATUS='';
      PARENT_PART_TYPE='AT24MAC402_SOT23_5';
      PARENT_PPT='AT24MAC402_SOT23_5';
      PARENT_PPT_PART='AT24MAC402_SOT23_5-A221-00002-FB,AT24MAC602-STUM-T';
  end_body;
end_primitive;
primitive 'BNO080_LGA_28-A246-00002-FB,BNA';
  pin
    'BOOTN':
      PIN_NUMBER='(4)';
      INPUT_LOAD='(-0.01,0.01)';
      PINUSE='IN';
    'CAP':
      PIN_NUMBER='(9)';
      OUTPUT_TYPE='(TS,TS)';
      BIDIRECTIONAL='TRUE';
      INPUT_LOAD='(-0.01,0.01)';
      OUTPUT_LOAD='(1.0,-1.0)';
      PINUSE='BI';
    'CLKSEL0':
      PIN_NUMBER='(10)';
      INPUT_LOAD='(-0.01,0.01)';
      PINUSE='IN';
    'ENV_SCL':
      PIN_NUMBER='(15)';
      OUTPUT_TYPE='(TS,TS)';
      BIDIRECTIONAL='TRUE';
      INPUT_LOAD='(-0.01,0.01)';
      OUTPUT_LOAD='(1.0,-1.0)';
      PINUSE='BI';
    'ENV_SDA':
      PIN_NUMBER='(16)';
      OUTPUT_TYPE='(TS,TS)';
      BIDIRECTIONAL='TRUE';
      INPUT_LOAD='(-0.01,0.01)';
      OUTPUT_LOAD='(1.0,-1.0)';
      PINUSE='BI';
    'GND_1':
      PIN_NUMBER='(2)';
      PINUSE='GROUND';
      NO_LOAD_CHECK='Both';
      NO_IO_CHECK='Both';
      NO_ASSERT_CHECK='TRUE';
      NO_DIR_CHECK='TRUE';
      ALLOW_CONNECT='TRUE';
    'GND_2':
      PIN_NUMBER='(25)';
      PINUSE='GROUND';
      NO_LOAD_CHECK='Both';
      NO_IO_CHECK='Both';
      NO_ASSERT_CHECK='TRUE';
      NO_DIR_CHECK='TRUE';
      ALLOW_CONNECT='TRUE';
    'H_CS*':
      PIN_NUMBER='(18)';
      INPUT_LOAD='(-0.01,0.01)';
      PINUSE='IN';
    'H_INTN':
      PIN_NUMBER='(14)';
      OUTPUT_LOAD='(1.0,-1.0)';
      PINUSE='OUT';
    'H_SCL/SCK/RX':
      PIN_NUMBER='(19)';
      OUTPUT_TYPE='(TS,TS)';
      BIDIRECTIONAL='TRUE';
      INPUT_LOAD='(-0.01,0.01)';
      OUTPUT_LOAD='(1.0,-1.0)';
      PINUSE='BI';
    'H_SDA/H_MISO/TX':
      PIN_NUMBER='(20)';
      OUTPUT_TYPE='(TS,TS)';
      BIDIRECTIONAL='TRUE';
      INPUT_LOAD='(-0.01,0.01)';
      OUTPUT_LOAD='(1.0,-1.0)';
      PINUSE='BI';
    'RST*':
      PIN_NUMBER='(11)';
      INPUT_LOAD='(-0.01,0.01)';
      PINUSE='IN';
    'PS0/WAKE':
      PIN_NUMBER='(6)';
      INPUT_LOAD='(-0.01,0.01)';
      PINUSE='IN';
    'PS1':
      PIN_NUMBER='(5)';
      INPUT_LOAD='(-0.01,0.01)';
      PINUSE='IN';
    'RESV_NC_1':
      PIN_NUMBER='(1)';
      PINUSE='NC';
      NO_LOAD_CHECK='Both';
      NO_IO_CHECK='Both';
      NO_ASSERT_CHECK='TRUE';
      NO_DIR_CHECK='TRUE';
      ALLOW_CONNECT='TRUE';
    'RESV_NC_2':
      PIN_NUMBER='(7)';
      INPUT_LOAD='(-0.01,0.01)';
      PINUSE='IN';
    'RESV_NC_3':
      PIN_NUMBER='(8)';
      PINUSE='NC';
      NO_LOAD_CHECK='Both';
      NO_IO_CHECK='Both';
      NO_ASSERT_CHECK='TRUE';
      NO_DIR_CHECK='TRUE';
      ALLOW_CONNECT='TRUE';
    'RESV_NC_4':
      PIN_NUMBER='(12)';
      PINUSE='NC';
      NO_LOAD_CHECK='Both';
      NO_IO_CHECK='Both';
      NO_ASSERT_CHECK='TRUE';
      NO_DIR_CHECK='TRUE';
      ALLOW_CONNECT='TRUE';
    'RESV_NC_5':
      PIN_NUMBER='(13)';
      PINUSE='NC';
      NO_LOAD_CHECK='Both';
      NO_IO_CHECK='Both';
      NO_ASSERT_CHECK='TRUE';
      NO_DIR_CHECK='TRUE';
      ALLOW_CONNECT='TRUE';
    'RESV_NC_6':
      PIN_NUMBER='(21)';
      PINUSE='NC';
      NO_LOAD_CHECK='Both';
      NO_IO_CHECK='Both';
      NO_ASSERT_CHECK='TRUE';
      NO_DIR_CHECK='TRUE';
      ALLOW_CONNECT='TRUE';
    'RESV_NC_7':
      PIN_NUMBER='(22)';
      PINUSE='NC';
      NO_LOAD_CHECK='Both';
      NO_IO_CHECK='Both';
      NO_ASSERT_CHECK='TRUE';
      NO_DIR_CHECK='TRUE';
      ALLOW_CONNECT='TRUE';
    'RESV_NC_8':
      PIN_NUMBER='(23)';
      PINUSE='NC';
      NO_LOAD_CHECK='Both';
      NO_IO_CHECK='Both';
      NO_ASSERT_CHECK='TRUE';
      NO_DIR_CHECK='TRUE';
      ALLOW_CONNECT='TRUE';
    'RESV_NC_9':
      PIN_NUMBER='(24)';
      PINUSE='NC';
      NO_LOAD_CHECK='Both';
      NO_IO_CHECK='Both';
      NO_ASSERT_CHECK='TRUE';
      NO_DIR_CHECK='TRUE';
      ALLOW_CONNECT='TRUE';
    'SA0/H_MOSI':
      PIN_NUMBER='(17)';
      INPUT_LOAD='(-0.01,0.01)';
      PINUSE='IN';
    'VDD':
      PIN_NUMBER='(3)';
      INPUT_LOAD='(-0.01,0.01)';
      PINUSE='IN';
    'VDDIO':
      PIN_NUMBER='(28)';
      INPUT_LOAD='(-0.01,0.01)';
      PINUSE='IN';
    'XIN32':
      PIN_NUMBER='(27)';
      INPUT_LOAD='(-0.01,0.01)';
      PINUSE='IN';
    'XOUT32/CLKSEL1':
      PIN_NUMBER='(26)';
      OUTPUT_LOAD='(1.0,-1.0)';
      PINUSE='OUT';
  end_pin;
  body
      PART_NAME='BNO080_LGA_28';
      BODY_NAME='BNO080_LGA_28';
      PHYS_DES_PREFIX='U';
      CLASS='IC';
      JEDEC_TYPE='LGA28_205X150_P0197';
      ALT_SYMBOLS='(LGA28_205X150_P0197)';
      DESCRIPTION='IC,BNO085,SIP,32-BIT ARM CORTEX,TRIAXIAL ACCELEROMETER,TRIAXI~
AL GYROSCOPE,MAGNETOMETER,SMT,LGA-28';
      CPN_STATUS='';
      PARENT_PART_TYPE='BNO080_LGA_28';
      PARENT_PPT='BNO080_LGA_28';
      PARENT_PPT_PART='BNO080_LGA_28-A246-00002-FB,BNO085';
  end_body;
end_primitive;
primitive 'CAPACITOR-G104-0A120-FJ,12PF,5%';
  pin
    '1':
      PIN_NUMBER='(1)';
      PINUSE='UNSPEC';
      NO_LOAD_CHECK='Both';
      NO_IO_CHECK='Both';
      NO_ASSERT_CHECK='TRUE';
      NO_DIR_CHECK='TRUE';
      ALLOW_CONNECT='TRUE';
    '2':
      PIN_NUMBER='(2)';
      PINUSE='UNSPEC';
      NO_LOAD_CHECK='Both';
      NO_IO_CHECK='Both';
      NO_ASSERT_CHECK='TRUE';
      NO_DIR_CHECK='TRUE';
      ALLOW_CONNECT='TRUE';
  end_pin;
  body
      PART_NAME='CAPACITOR';
      BODY_NAME='CAPACITOR';
      PHYS_DES_PREFIX='C';
      CLASS='DISCRETE';
      JEDEC_TYPE='SMC_0201R';
      ALT_SYMBOLS='(SMC_0201R_C)';
      DESCRIPTION='CAP,12PF,5%,50V,C0G,0201';
      CPN_STATUS='';
      PARENT_PART_TYPE='CAPACITOR';
      PARENT_PPT='CAPACITOR';
      PARENT_PPT_PART='CAPACITOR-G104-0A120-FJ,12PF,5%';
  end_body;
end_primitive;
primitive 'CAPACITOR-G104-0A180-FJ,18PF,5%';
  pin
    '1':
      PIN_NUMBER='(1)';
      PINUSE='UNSPEC';
      NO_LOAD_CHECK='Both';
      NO_IO_CHECK='Both';
      NO_ASSERT_CHECK='TRUE';
      NO_DIR_CHECK='TRUE';
      ALLOW_CONNECT='TRUE';
    '2':
      PIN_NUMBER='(2)';
      PINUSE='UNSPEC';
      NO_LOAD_CHECK='Both';
      NO_IO_CHECK='Both';
      NO_ASSERT_CHECK='TRUE';
      NO_DIR_CHECK='TRUE';
      ALLOW_CONNECT='TRUE';
  end_pin;
  body
      PART_NAME='CAPACITOR';
      BODY_NAME='CAPACITOR';
      PHYS_DES_PREFIX='C';
      CLASS='DISCRETE';
      JEDEC_TYPE='SMC_0201R';
      ALT_SYMBOLS='(SMC_0201R_C)';
      DESCRIPTION='CAP,18PF,5%,50V,C0G,0201';
      CPN_STATUS='';
      PARENT_PART_TYPE='CAPACITOR';
      PARENT_PPT='CAPACITOR';
      PARENT_PPT_PART='CAPACITOR-G104-0A180-FJ,18PF,5%';
  end_body;
end_primitive;
primitive 'CAPACITOR-G104-0B101-FK,100PF,A';
  pin
    '1':
      PIN_NUMBER='(1)';
      PINUSE='UNSPEC';
      NO_LOAD_CHECK='Both';
      NO_IO_CHECK='Both';
      NO_ASSERT_CHECK='TRUE';
      NO_DIR_CHECK='TRUE';
      ALLOW_CONNECT='TRUE';
    '2':
      PIN_NUMBER='(2)';
      PINUSE='UNSPEC';
      NO_LOAD_CHECK='Both';
      NO_IO_CHECK='Both';
      NO_ASSERT_CHECK='TRUE';
      NO_DIR_CHECK='TRUE';
      ALLOW_CONNECT='TRUE';
  end_pin;
  body
      PART_NAME='CAPACITOR';
      BODY_NAME='CAPACITOR';
      PHYS_DES_PREFIX='C';
      CLASS='DISCRETE';
      JEDEC_TYPE='SMC_0201R';
      ALT_SYMBOLS='(SMC_0201R_C)';
      DESCRIPTION='CAP,100PF,10%,50V,X7R,0201';
      CPN_STATUS='';
      PARENT_PART_TYPE='CAPACITOR';
      PARENT_PPT='CAPACITOR';
      PARENT_PPT_PART='CAPACITOR-G104-0B101-FK,100PF,10%';
  end_body;
end_primitive;
primitive 'CAPACITOR-G104-0B103-EK,0.01UFA';
  pin
    '1':
      PIN_NUMBER='(1)';
      PINUSE='UNSPEC';
      NO_LOAD_CHECK='Both';
      NO_IO_CHECK='Both';
      NO_ASSERT_CHECK='TRUE';
      NO_DIR_CHECK='TRUE';
      ALLOW_CONNECT='TRUE';
    '2':
      PIN_NUMBER='(2)';
      PINUSE='UNSPEC';
      NO_LOAD_CHECK='Both';
      NO_IO_CHECK='Both';
      NO_ASSERT_CHECK='TRUE';
      NO_DIR_CHECK='TRUE';
      ALLOW_CONNECT='TRUE';
  end_pin;
  body
      PART_NAME='CAPACITOR';
      BODY_NAME='CAPACITOR';
      PHYS_DES_PREFIX='C';
      CLASS='DISCRETE';
      JEDEC_TYPE='SMC_0201R';
      ALT_SYMBOLS='(SMC_0201R_C)';
      DESCRIPTION='CAP,0.01UF,10%,25V,X7R,0201';
      CPN_STATUS='';
      PARENT_PART_TYPE='CAPACITOR';
      PARENT_PPT='CAPACITOR';
      PARENT_PPT_PART='CAPACITOR-G104-0B103-EK,0.01UF,10%';
  end_body;
end_primitive;
primitive 'CAPACITOR-G104-0B472-EK,4700PFA';
  pin
    '1':
      PIN_NUMBER='(1)';
      PINUSE='UNSPEC';
      NO_LOAD_CHECK='Both';
      NO_IO_CHECK='Both';
      NO_ASSERT_CHECK='TRUE';
      NO_DIR_CHECK='TRUE';
      ALLOW_CONNECT='TRUE';
    '2':
      PIN_NUMBER='(2)';
      PINUSE='UNSPEC';
      NO_LOAD_CHECK='Both';
      NO_IO_CHECK='Both';
      NO_ASSERT_CHECK='TRUE';
      NO_DIR_CHECK='TRUE';
      ALLOW_CONNECT='TRUE';
  end_pin;
  body
      PART_NAME='CAPACITOR';
      BODY_NAME='CAPACITOR';
      PHYS_DES_PREFIX='C';
      CLASS='DISCRETE';
      JEDEC_TYPE='SMC_0201R';
      ALT_SYMBOLS='(SMC_0201R_C)';
      DESCRIPTION='CAP,4700PF,10%,25V,X7R,0201';
      CPN_STATUS='';
      PARENT_PART_TYPE='CAPACITOR';
      PARENT_PPT='CAPACITOR';
      PARENT_PPT_PART='CAPACITOR-G104-0B472-EK,4700PF,10%';
  end_body;
end_primitive;
primitive 'CAPACITOR-G104-0F224-BK,0.22UFA';
  pin
    '1':
      PIN_NUMBER='(1)';
      PINUSE='UNSPEC';
      NO_LOAD_CHECK='Both';
      NO_IO_CHECK='Both';
      NO_ASSERT_CHECK='TRUE';
      NO_DIR_CHECK='TRUE';
      ALLOW_CONNECT='TRUE';
    '2':
      PIN_NUMBER='(2)';
      PINUSE='UNSPEC';
      NO_LOAD_CHECK='Both';
      NO_IO_CHECK='Both';
      NO_ASSERT_CHECK='TRUE';
      NO_DIR_CHECK='TRUE';
      ALLOW_CONNECT='TRUE';
  end_pin;
  body
      PART_NAME='CAPACITOR';
      BODY_NAME='CAPACITOR';
      PHYS_DES_PREFIX='C';
      CLASS='DISCRETE';
      JEDEC_TYPE='SMC_0201R';
      ALT_SYMBOLS='(SMC_0201R_C)';
      DESCRIPTION='CAP,0.22UF,10%,6.3V,X6S,0201';
      CPN_STATUS='';
      PARENT_PART_TYPE='CAPACITOR';
      PARENT_PPT='CAPACITOR';
      PARENT_PPT_PART='CAPACITOR-G104-0F224-BK,0.22UF,10%';
  end_body;
end_primitive;
primitive 'CAPACITOR-G105-0A102-FJ,1000PFA';
  pin
    '1':
      PIN_NUMBER='(1)';
      PINUSE='UNSPEC';
      NO_LOAD_CHECK='Both';
      NO_IO_CHECK='Both';
      NO_ASSERT_CHECK='TRUE';
      NO_DIR_CHECK='TRUE';
      ALLOW_CONNECT='TRUE';
    '2':
      PIN_NUMBER='(2)';
      PINUSE='UNSPEC';
      NO_LOAD_CHECK='Both';
      NO_IO_CHECK='Both';
      NO_ASSERT_CHECK='TRUE';
      NO_DIR_CHECK='TRUE';
      ALLOW_CONNECT='TRUE';
  end_pin;
  body
      PART_NAME='CAPACITOR';
      BODY_NAME='CAPACITOR';
      PHYS_DES_PREFIX='C';
      CLASS='DISCRETE';
      JEDEC_TYPE='SMC_0402R_H022';
      ALT_SYMBOLS='(SMC_0402R_C_H022,SMC_0402R_V2_H022,C0402-1MM-TRIANGLE-S0,C04~
02-P8MM-S0)';
      DESCRIPTION='CAP,1000PF,5%,50V,C0G,0402';
      CPN_STATUS='';
      PARENT_PART_TYPE='CAPACITOR';
      PARENT_PPT='CAPACITOR';
      PARENT_PPT_PART='CAPACITOR-G105-0A102-FJ,1000PF,5%';
  end_body;
end_primitive;
primitive 'CAPACITOR-G105-0B104-CK,0.1UF,A';
  pin
    '1':
      PIN_NUMBER='(1)';
      PINUSE='UNSPEC';
      NO_LOAD_CHECK='Both';
      NO_IO_CHECK='Both';
      NO_ASSERT_CHECK='TRUE';
      NO_DIR_CHECK='TRUE';
      ALLOW_CONNECT='TRUE';
    '2':
      PIN_NUMBER='(2)';
      PINUSE='UNSPEC';
      NO_LOAD_CHECK='Both';
      NO_IO_CHECK='Both';
      NO_ASSERT_CHECK='TRUE';
      NO_DIR_CHECK='TRUE';
      ALLOW_CONNECT='TRUE';
  end_pin;
  body
      PART_NAME='CAPACITOR';
      BODY_NAME='CAPACITOR';
      PHYS_DES_PREFIX='C';
      CLASS='DISCRETE';
      JEDEC_TYPE='SMC_0402R_H022';
      ALT_SYMBOLS='(SMC_0402R_C_H022,C0402_BGA,C0402-0P8MM-45DG,C0402-1MM-TRIANG~
LE-S0)';
      DESCRIPTION='CAP,0.1UF,10%,10V,X7R,0402';
      CPN_STATUS='';
      PARENT_PART_TYPE='CAPACITOR';
      PARENT_PPT='CAPACITOR';
      PARENT_PPT_PART='CAPACITOR-G105-0B104-CK,0.1UF,10%';
  end_body;
end_primitive;
primitive 'CAPACITOR-G105-0B104-EK,0.1UF,A';
  pin
    '1':
      PIN_NUMBER='(1)';
      PINUSE='UNSPEC';
      NO_LOAD_CHECK='Both';
      NO_IO_CHECK='Both';
      NO_ASSERT_CHECK='TRUE';
      NO_DIR_CHECK='TRUE';
      ALLOW_CONNECT='TRUE';
    '2':
      PIN_NUMBER='(2)';
      PINUSE='UNSPEC';
      NO_LOAD_CHECK='Both';
      NO_IO_CHECK='Both';
      NO_ASSERT_CHECK='TRUE';
      NO_DIR_CHECK='TRUE';
      ALLOW_CONNECT='TRUE';
  end_pin;
  body
      PART_NAME='CAPACITOR';
      BODY_NAME='CAPACITOR';
      PHYS_DES_PREFIX='C';
      CLASS='DISCRETE';
      JEDEC_TYPE='SMC_0402R_H022';
      ALT_SYMBOLS='(SMC_0402R_C_H022,C0402-1MM-TRIANGLE-S0,C0402-P8MM-S0)';
      DESCRIPTION='CAP,0.1UF,10%,25V,X7R,CER,0402';
      CPN_STATUS='';
      PARENT_PART_TYPE='CAPACITOR';
      PARENT_PPT='CAPACITOR';
      PARENT_PPT_PART='CAPACITOR-G105-0B104-EK,0.1UF,10%';
  end_body;
end_primitive;
primitive 'CAPACITOR-G105-0B222-FK,2200PFA';
  pin
    '1':
      PIN_NUMBER='(1)';
      PINUSE='UNSPEC';
      NO_LOAD_CHECK='Both';
      NO_IO_CHECK='Both';
      NO_ASSERT_CHECK='TRUE';
      NO_DIR_CHECK='TRUE';
      ALLOW_CONNECT='TRUE';
    '2':
      PIN_NUMBER='(2)';
      PINUSE='UNSPEC';
      NO_LOAD_CHECK='Both';
      NO_IO_CHECK='Both';
      NO_ASSERT_CHECK='TRUE';
      NO_DIR_CHECK='TRUE';
      ALLOW_CONNECT='TRUE';
  end_pin;
  body
      PART_NAME='CAPACITOR';
      BODY_NAME='CAPACITOR';
      PHYS_DES_PREFIX='C';
      CLASS='DISCRETE';
      JEDEC_TYPE='SMC_0402R_H022';
      ALT_SYMBOLS='(SMC_0402R_C_H022)';
      DESCRIPTION='CAP,2200PF,10%,X7R,50V,0402';
      CPN_STATUS='';
      PARENT_PART_TYPE='CAPACITOR';
      PARENT_PPT='CAPACITOR';
      PARENT_PPT_PART='CAPACITOR-G105-0B222-FK,2200PF,10%';
  end_body;
end_primitive;
primitive 'CAPACITOR-G105-0B223-EK,0.022UA';
  pin
    '1':
      PIN_NUMBER='(1)';
      PINUSE='UNSPEC';
      NO_LOAD_CHECK='Both';
      NO_IO_CHECK='Both';
      NO_ASSERT_CHECK='TRUE';
      NO_DIR_CHECK='TRUE';
      ALLOW_CONNECT='TRUE';
    '2':
      PIN_NUMBER='(2)';
      PINUSE='UNSPEC';
      NO_LOAD_CHECK='Both';
      NO_IO_CHECK='Both';
      NO_ASSERT_CHECK='TRUE';
      NO_DIR_CHECK='TRUE';
      ALLOW_CONNECT='TRUE';
  end_pin;
  body
      PART_NAME='CAPACITOR';
      BODY_NAME='CAPACITOR';
      PHYS_DES_PREFIX='C';
      CLASS='DISCRETE';
      JEDEC_TYPE='SMC_0402R_H022';
      ALT_SYMBOLS='(SMC_0402R_C_H022)';
      DESCRIPTION='CAP,0.022UF,10%,25V,X7R,0402';
      CPN_STATUS='';
      PARENT_PART_TYPE='CAPACITOR';
      PARENT_PPT='CAPACITOR';
      PARENT_PPT_PART='CAPACITOR-G105-0B223-EK,0.022UF,10%';
  end_body;
end_primitive;
primitive 'CAPACITOR-G105-0B224-DK,0.22UFA';
  pin
    '1':
      PIN_NUMBER='(1)';
      PINUSE='UNSPEC';
      NO_LOAD_CHECK='Both';
      NO_IO_CHECK='Both';
      NO_ASSERT_CHECK='TRUE';
      NO_DIR_CHECK='TRUE';
      ALLOW_CONNECT='TRUE';
    '2':
      PIN_NUMBER='(2)';
      PINUSE='UNSPEC';
      NO_LOAD_CHECK='Both';
      NO_IO_CHECK='Both';
      NO_ASSERT_CHECK='TRUE';
      NO_DIR_CHECK='TRUE';
      ALLOW_CONNECT='TRUE';
  end_pin;
  body
      PART_NAME='CAPACITOR';
      BODY_NAME='CAPACITOR';
      PHYS_DES_PREFIX='C';
      CLASS='DISCRETE';
      JEDEC_TYPE='SMC_0402R_H022';
      ALT_SYMBOLS='(SMC_0402R_C_H022)';
      DESCRIPTION='CAP,0.22UF,10%,X7R,16V,0402';
      CPN_STATUS='';
      PARENT_PART_TYPE='CAPACITOR';
      PARENT_PPT='CAPACITOR';
      PARENT_PPT_PART='CAPACITOR-G105-0B224-DK,0.22UF,10%';
  end_body;
end_primitive;
primitive 'CAPACITOR-G105-0C106-BM,10UF,2A';
  pin
    '1':
      PIN_NUMBER='(1)';
      PINUSE='UNSPEC';
      NO_LOAD_CHECK='Both';
      NO_IO_CHECK='Both';
      NO_ASSERT_CHECK='TRUE';
      NO_DIR_CHECK='TRUE';
      ALLOW_CONNECT='TRUE';
    '2':
      PIN_NUMBER='(2)';
      PINUSE='UNSPEC';
      NO_LOAD_CHECK='Both';
      NO_IO_CHECK='Both';
      NO_ASSERT_CHECK='TRUE';
      NO_DIR_CHECK='TRUE';
      ALLOW_CONNECT='TRUE';
  end_pin;
  body
      PART_NAME='CAPACITOR';
      BODY_NAME='CAPACITOR';
      PHYS_DES_PREFIX='C';
      CLASS='DISCRETE';
      JEDEC_TYPE='SMC_0402R_H022';
      ALT_SYMBOLS='(SMC_0402R_C_H022,C0402_BGA,C0402-0P8MM-45DG,C0402-P8MM-S0,C0~
402-1MM-TRIANGLE-S0)';
      DESCRIPTION='CAP,10UF,20%,6.3V,X5R,0402';
      CPN_STATUS='';
      PARENT_PART_TYPE='CAPACITOR';
      PARENT_PPT='CAPACITOR';
      PARENT_PPT_PART='CAPACITOR-G105-0C106-BM,10UF,20%';
  end_body;
end_primitive;
primitive 'CAPACITOR-G105-0F475-BM,4.7UF,A';
  pin
    '1':
      PIN_NUMBER='(1)';
      PINUSE='UNSPEC';
      NO_LOAD_CHECK='Both';
      NO_IO_CHECK='Both';
      NO_ASSERT_CHECK='TRUE';
      NO_DIR_CHECK='TRUE';
      ALLOW_CONNECT='TRUE';
    '2':
      PIN_NUMBER='(2)';
      PINUSE='UNSPEC';
      NO_LOAD_CHECK='Both';
      NO_IO_CHECK='Both';
      NO_ASSERT_CHECK='TRUE';
      NO_DIR_CHECK='TRUE';
      ALLOW_CONNECT='TRUE';
  end_pin;
  body
      PART_NAME='CAPACITOR';
      BODY_NAME='CAPACITOR';
      PHYS_DES_PREFIX='C';
      CLASS='DISCRETE';
      JEDEC_TYPE='SMC_0402R_H026';
      ALT_SYMBOLS='(SMC_0402R_C_H026,C0402_BGA,C0402-0P8MM-45DG,C0402-1MM-TRIANG~
LE-S0)';
      DESCRIPTION='CAP,4.7UF,20%,6.3V,X6S,0402';
      CPN_STATUS='';
      PARENT_PART_TYPE='CAPACITOR';
      PARENT_PPT='CAPACITOR';
      PARENT_PPT_PART='CAPACITOR-G105-0F475-BM,4.7UF,20%';
  end_body;
end_primitive;
primitive 'CAPACITOR-G107-0F106-EM,10UF,2A';
  pin
    '1':
      PIN_NUMBER='(1)';
      PINUSE='UNSPEC';
      NO_LOAD_CHECK='Both';
      NO_IO_CHECK='Both';
      NO_ASSERT_CHECK='TRUE';
      NO_DIR_CHECK='TRUE';
      ALLOW_CONNECT='TRUE';
    '2':
      PIN_NUMBER='(2)';
      PINUSE='UNSPEC';
      NO_LOAD_CHECK='Both';
      NO_IO_CHECK='Both';
      NO_ASSERT_CHECK='TRUE';
      NO_DIR_CHECK='TRUE';
      ALLOW_CONNECT='TRUE';
  end_pin;
  body
      PART_NAME='CAPACITOR';
      BODY_NAME='CAPACITOR';
      PHYS_DES_PREFIX='C';
      CLASS='DISCRETE';
      JEDEC_TYPE='SMC_0805R_H057';
      ALT_SYMBOLS='(SMC_0805R_H057)';
      DESCRIPTION='CAP,10UF,20%,25V,X6S,0805';
      CPN_STATUS='';
      PARENT_PART_TYPE='CAPACITOR';
      PARENT_PPT='CAPACITOR';
      PARENT_PPT_PART='CAPACITOR-G107-0F106-EM,10UF,20%';
  end_body;
end_primitive;
primitive 'CAPACITOR-G107-0F226-CM,22UF,2A';
  pin
    '1':
      PIN_NUMBER='(1)';
      PINUSE='UNSPEC';
      NO_LOAD_CHECK='Both';
      NO_IO_CHECK='Both';
      NO_ASSERT_CHECK='TRUE';
      NO_DIR_CHECK='TRUE';
      ALLOW_CONNECT='TRUE';
    '2':
      PIN_NUMBER='(2)';
      PINUSE='UNSPEC';
      NO_LOAD_CHECK='Both';
      NO_IO_CHECK='Both';
      NO_ASSERT_CHECK='TRUE';
      NO_DIR_CHECK='TRUE';
      ALLOW_CONNECT='TRUE';
  end_pin;
  body
      PART_NAME='CAPACITOR';
      BODY_NAME='CAPACITOR';
      PHYS_DES_PREFIX='C';
      CLASS='DISCRETE';
      JEDEC_TYPE='SMC_0805R_H057';
      ALT_SYMBOLS='(SMC_0805R_H057)';
      DESCRIPTION='CAP,22UF,20%,10V,X6S,0805';
      CPN_STATUS='';
      PARENT_PART_TYPE='CAPACITOR';
      PARENT_PPT='CAPACITOR';
      PARENT_PPT_PART='CAPACITOR-G107-0F226-CM,22UF,20%';
  end_body;
end_primitive;
primitive 'CAPACITOR-G107-0F476-AM,47UF,2A';
  pin
    '1':
      PIN_NUMBER='(1)';
      PINUSE='UNSPEC';
      NO_LOAD_CHECK='Both';
      NO_IO_CHECK='Both';
      NO_ASSERT_CHECK='TRUE';
      NO_DIR_CHECK='TRUE';
      ALLOW_CONNECT='TRUE';
    '2':
      PIN_NUMBER='(2)';
      PINUSE='UNSPEC';
      NO_LOAD_CHECK='Both';
      NO_IO_CHECK='Both';
      NO_ASSERT_CHECK='TRUE';
      NO_DIR_CHECK='TRUE';
      ALLOW_CONNECT='TRUE';
  end_pin;
  body
      PART_NAME='CAPACITOR';
      BODY_NAME='CAPACITOR';
      PHYS_DES_PREFIX='C';
      CLASS='DISCRETE';
      JEDEC_TYPE='SMC_0805R_H057';
      ALT_SYMBOLS='(SMC_0805R_H057)';
      DESCRIPTION='CAP,47UF,20%,4V,X6S,0805';
      CPN_STATUS='';
      PARENT_PART_TYPE='CAPACITOR';
      PARENT_PPT='CAPACITOR';
      PARENT_PPT_PART='CAPACITOR-G107-0F476-AM,47UF,20%';
  end_body;
end_primitive;
primitive 'CAPACITOR-G109-0G107-BM,100UF,A';
  pin
    '1':
      PIN_NUMBER='(1)';
      PINUSE='UNSPEC';
      NO_LOAD_CHECK='Both';
      NO_IO_CHECK='Both';
      NO_ASSERT_CHECK='TRUE';
      NO_DIR_CHECK='TRUE';
      ALLOW_CONNECT='TRUE';
    '2':
      PIN_NUMBER='(2)';
      PINUSE='UNSPEC';
      NO_LOAD_CHECK='Both';
      NO_IO_CHECK='Both';
      NO_ASSERT_CHECK='TRUE';
      NO_DIR_CHECK='TRUE';
      ALLOW_CONNECT='TRUE';
  end_pin;
  body
      PART_NAME='CAPACITOR';
      BODY_NAME='CAPACITOR';
      PHYS_DES_PREFIX='C';
      CLASS='DISCRETE';
      JEDEC_TYPE='SMC_1210R_H110';
      ALT_SYMBOLS='(SMC_1210R_H110)';
      DESCRIPTION='CAP,100UF,20%,6.3V,X7S,1210';
      CPN_STATUS='';
      PARENT_PART_TYPE='CAPACITOR';
      PARENT_PPT='CAPACITOR';
      PARENT_PPT_PART='CAPACITOR-G109-0G107-BM,100UF,20%';
  end_body;
end_primitive;
primitive 'CAT93C46VI_GT3_SOIC8-G221-1007A';
  pin
    'CS':
      PIN_NUMBER='(1,0)';
      OUTPUT_TYPE='(TS,TS)';
      BIDIRECTIONAL='TRUE';
      INPUT_LOAD='(-0.01,0.01)';
      OUTPUT_LOAD='(1.0,-1.0)';
      PINUSE='BI';
    'SK':
      PIN_NUMBER='(2,0)';
      INPUT_LOAD='(-0.01,0.01)';
      PINUSE='IN';
    'DI':
      PIN_NUMBER='(3,0)';
      INPUT_LOAD='(-0.01,0.01)';
      PINUSE='IN';
    'DO':
      PIN_NUMBER='(4,0)';
      OUTPUT_LOAD='(1.0,-1.0)';
      PINUSE='OUT';
    'ORG':
      PIN_NUMBER='(6,0)';
      OUTPUT_TYPE='(TS,TS)';
      BIDIRECTIONAL='TRUE';
      INPUT_LOAD='(-0.01,0.01)';
      OUTPUT_LOAD='(1.0,-1.0)';
      PINUSE='BI';
    'NC':
      PIN_NUMBER='(7,0)';
      PINUSE='NC';
      NO_LOAD_CHECK='Both';
      NO_IO_CHECK='Both';
      NO_ASSERT_CHECK='TRUE';
      NO_DIR_CHECK='TRUE';
      ALLOW_CONNECT='TRUE';
    'VCC':
      PIN_NUMBER='(0,8)';
      PINUSE='POWER';
      NO_LOAD_CHECK='Both';
      NO_IO_CHECK='Both';
      NO_ASSERT_CHECK='TRUE';
      NO_DIR_CHECK='TRUE';
      ALLOW_CONNECT='TRUE';
    'GND':
      PIN_NUMBER='(0,5)';
      PINUSE='GROUND';
      NO_LOAD_CHECK='Both';
      NO_IO_CHECK='Both';
      NO_ASSERT_CHECK='TRUE';
      NO_DIR_CHECK='TRUE';
      ALLOW_CONNECT='TRUE';
  end_pin;
  body
      PART_NAME='CAT93C46VI_GT3_SOIC8';
      BODY_NAME='CAT93C46VI_GT3_SOIC8';
      PHYS_DES_PREFIX='U';
      CLASS='IC';
      JEDEC_TYPE='SOP8_154_P050_V1';
      ALT_SYMBOLS='(SOP8_154_P050_V1)';
      DESCRIPTION='IC,AT93C46D,1KBIT,THREE-WIRE EEPROM,1.8V-5.5V,SO8';
      CPN_STATUS='';
      PARENT_PART_TYPE='CAT93C46VI_GT3_SOIC8';
      PARENT_PPT='CAT93C46VI_GT3_SOIC8';
      PARENT_PPT_PART='CAT93C46VI_GT3_SOIC8-G221-10075-01';
  end_body;
end_primitive;
primitive 'CL1001485A-G122-00019-01';
  pin
    '1':
      PIN_NUMBER='(1)';
      OUTPUT_TYPE='(TS,TS)';
      BIDIRECTIONAL='TRUE';
      INPUT_LOAD='(-0.01,0.01)';
      OUTPUT_LOAD='(1.0,-1.0)';
      PINUSE='BI';
    '2':
      PIN_NUMBER='(2)';
      OUTPUT_TYPE='(TS,TS)';
      BIDIRECTIONAL='TRUE';
      INPUT_LOAD='(-0.01,0.01)';
      OUTPUT_LOAD='(1.0,-1.0)';
      PINUSE='BI';
    '3':
      PIN_NUMBER='(3)';
      OUTPUT_TYPE='(TS,TS)';
      BIDIRECTIONAL='TRUE';
      INPUT_LOAD='(-0.01,0.01)';
      OUTPUT_LOAD='(1.0,-1.0)';
      PINUSE='BI';
    '4':
      PIN_NUMBER='(4)';
      OUTPUT_TYPE='(TS,TS)';
      BIDIRECTIONAL='TRUE';
      INPUT_LOAD='(-0.01,0.01)';
      OUTPUT_LOAD='(1.0,-1.0)';
      PINUSE='BI';
    '5':
      PIN_NUMBER='(5)';
      OUTPUT_TYPE='(TS,TS)';
      BIDIRECTIONAL='TRUE';
      INPUT_LOAD='(-0.01,0.01)';
      OUTPUT_LOAD='(1.0,-1.0)';
      PINUSE='BI';
    '6':
      PIN_NUMBER='(6)';
      OUTPUT_TYPE='(TS,TS)';
      BIDIRECTIONAL='TRUE';
      INPUT_LOAD='(-0.01,0.01)';
      OUTPUT_LOAD='(1.0,-1.0)';
      PINUSE='BI';
  end_pin;
  body
      PART_NAME='CL1001485A';
      BODY_NAME='CL1001485A';
      PHYS_DES_PREFIX='U';
      CLASS='DISCRETE';
      JEDEC_TYPE='SOT23_6';
      ALT_SYMBOLS='(SOT23_6)';
      DESCRIPTION='DIODE ARRAY, LOW CAPACITANCE TVS, GBE PHY PROTECTION CHIP';
      CPN_STATUS='NFND';
      PARENT_PART_TYPE='CL1001485A';
      PARENT_PPT='CL1001485A';
      PARENT_PPT_PART='CL1001485A-G122-00019-01';
  end_body;
end_primitive;
primitive 'CL5003148A-G220-10019-01';
  pin
    'A':
      PIN_NUMBER='(1,0)';
      INPUT_LOAD='(-0.01,0.01)';
      PINUSE='IN';
    'B':
      PIN_NUMBER='(2,0)';
      INPUT_LOAD='(-0.01,0.01)';
      PINUSE='IN';
    'Y':
      PIN_NUMBER='(4,0)';
      OUTPUT_LOAD='(1.0,-1.0)';
      PINUSE='OUT';
    'GND':
      PIN_NUMBER='(0,3)';
      PINUSE='GROUND';
      NO_LOAD_CHECK='Both';
      NO_IO_CHECK='Both';
      NO_ASSERT_CHECK='TRUE';
      NO_DIR_CHECK='TRUE';
      ALLOW_CONNECT='TRUE';
    'VCC':
      PIN_NUMBER='(0,5)';
      PINUSE='POWER';
      NO_LOAD_CHECK='Both';
      NO_IO_CHECK='Both';
      NO_ASSERT_CHECK='TRUE';
      NO_DIR_CHECK='TRUE';
      ALLOW_CONNECT='TRUE';
  end_pin;
  body
      PART_NAME='CL5003148A';
      BODY_NAME='CL5003148A';
      PHYS_DES_PREFIX='U';
      CLASS='IC';
      JEDEC_TYPE='SC70_5V1';
      ALT_SYMBOLS='(SC70_5V1)';
      DESCRIPTION='IC,74LVC1G32,SINGLE 2_INPUT POSITIVE OR GATE,SC70_5';
      PARENT_PART_TYPE='CL5003148A';
      PARENT_PPT='CL5003148A';
      PARENT_PPT_PART='CL5003148A-G220-10019-01';
  end_body;
end_primitive;
primitive 'CONN_64P_GF-S_M_EF64_PCIE_P039A';
  pin
    'P_12V1':
      PIN_NUMBER='(B1)';
      PINUSE='POWER';
      NO_LOAD_CHECK='Both';
      NO_IO_CHECK='Both';
      NO_ASSERT_CHECK='TRUE';
      NO_DIR_CHECK='TRUE';
      ALLOW_CONNECT='TRUE';
    'P_12V2':
      PIN_NUMBER='(B2)';
      PINUSE='POWER';
      NO_LOAD_CHECK='Both';
      NO_IO_CHECK='Both';
      NO_ASSERT_CHECK='TRUE';
      NO_DIR_CHECK='TRUE';
      ALLOW_CONNECT='TRUE';
    'P_12V4':
      PIN_NUMBER='(B3)';
      PINUSE='POWER';
      NO_LOAD_CHECK='Both';
      NO_IO_CHECK='Both';
      NO_ASSERT_CHECK='TRUE';
      NO_DIR_CHECK='TRUE';
      ALLOW_CONNECT='TRUE';
    'GND1':
      PIN_NUMBER='(B4)';
      PINUSE='GROUND';
      NO_LOAD_CHECK='Both';
      NO_IO_CHECK='Both';
      NO_ASSERT_CHECK='TRUE';
      NO_DIR_CHECK='TRUE';
      ALLOW_CONNECT='TRUE';
    'SMCLK':
      PIN_NUMBER='(B5)';
      OUTPUT_TYPE='(TS,TS)';
      BIDIRECTIONAL='TRUE';
      INPUT_LOAD='(-0.01,0.01)';
      OUTPUT_LOAD='(1.0,-1.0)';
      PINUSE='BI';
    'SMDAT':
      PIN_NUMBER='(B6)';
      OUTPUT_TYPE='(TS,TS)';
      BIDIRECTIONAL='TRUE';
      INPUT_LOAD='(-0.01,0.01)';
      OUTPUT_LOAD='(1.0,-1.0)';
      PINUSE='BI';
    'GND3':
      PIN_NUMBER='(B7)';
      PINUSE='GROUND';
      NO_LOAD_CHECK='Both';
      NO_IO_CHECK='Both';
      NO_ASSERT_CHECK='TRUE';
      NO_DIR_CHECK='TRUE';
      ALLOW_CONNECT='TRUE';
    'P_3V3_1':
      PIN_NUMBER='(B8)';
      PINUSE='POWER';
      NO_LOAD_CHECK='Both';
      NO_IO_CHECK='Both';
      NO_ASSERT_CHECK='TRUE';
      NO_DIR_CHECK='TRUE';
      ALLOW_CONNECT='TRUE';
    'JTAG1':
      PIN_NUMBER='(B9)';
      OUTPUT_TYPE='(TS,TS)';
      BIDIRECTIONAL='TRUE';
      INPUT_LOAD='(-0.01,0.01)';
      OUTPUT_LOAD='(1.0,-1.0)';
      PINUSE='BI';
    'P_3V3AUX':
      PIN_NUMBER='(B10)';
      PINUSE='POWER';
      NO_LOAD_CHECK='Both';
      NO_IO_CHECK='Both';
      NO_ASSERT_CHECK='TRUE';
      NO_DIR_CHECK='TRUE';
      ALLOW_CONNECT='TRUE';
    'WAKE*':
      PIN_NUMBER='(B11)';
      OUTPUT_TYPE='(TS,TS)';
      BIDIRECTIONAL='TRUE';
      INPUT_LOAD='(-0.01,0.01)';
      OUTPUT_LOAD='(1.0,-1.0)';
      PINUSE='BI';
    'RSVD1':
      PIN_NUMBER='(B12)';
      OUTPUT_TYPE='(TS,TS)';
      BIDIRECTIONAL='TRUE';
      INPUT_LOAD='(-0.01,0.01)';
      OUTPUT_LOAD='(1.0,-1.0)';
      PINUSE='BI';
    'GND5':
      PIN_NUMBER='(B13)';
      PINUSE='GROUND';
      NO_LOAD_CHECK='Both';
      NO_IO_CHECK='Both';
      NO_ASSERT_CHECK='TRUE';
      NO_DIR_CHECK='TRUE';
      ALLOW_CONNECT='TRUE';
    'PETP0':
      PIN_NUMBER='(B14)';
      OUTPUT_TYPE='(TS,TS)';
      BIDIRECTIONAL='TRUE';
      INPUT_LOAD='(-0.01,0.01)';
      OUTPUT_LOAD='(1.0,-1.0)';
      PINUSE='BI';
    'PETN0':
      PIN_NUMBER='(B15)';
      OUTPUT_TYPE='(TS,TS)';
      BIDIRECTIONAL='TRUE';
      INPUT_LOAD='(-0.01,0.01)';
      OUTPUT_LOAD='(1.0,-1.0)';
      PINUSE='BI';
    'GND7':
      PIN_NUMBER='(B16)';
      PINUSE='GROUND';
      NO_LOAD_CHECK='Both';
      NO_IO_CHECK='Both';
      NO_ASSERT_CHECK='TRUE';
      NO_DIR_CHECK='TRUE';
      ALLOW_CONNECT='TRUE';
    'PRSNT2_1*':
      PIN_NUMBER='(B17)';
      OUTPUT_TYPE='(TS,TS)';
      BIDIRECTIONAL='TRUE';
      INPUT_LOAD='(-0.01,0.01)';
      OUTPUT_LOAD='(1.0,-1.0)';
      PINUSE='BI';
    'GND9':
      PIN_NUMBER='(B18)';
      PINUSE='GROUND';
      NO_LOAD_CHECK='Both';
      NO_IO_CHECK='Both';
      NO_ASSERT_CHECK='TRUE';
      NO_DIR_CHECK='TRUE';
      ALLOW_CONNECT='TRUE';
    'PETP1':
      PIN_NUMBER='(B19)';
      OUTPUT_TYPE='(TS,TS)';
      BIDIRECTIONAL='TRUE';
      INPUT_LOAD='(-0.01,0.01)';
      OUTPUT_LOAD='(1.0,-1.0)';
      PINUSE='BI';
    'PETN1':
      PIN_NUMBER='(B20)';
      OUTPUT_TYPE='(TS,TS)';
      BIDIRECTIONAL='TRUE';
      INPUT_LOAD='(-0.01,0.01)';
      OUTPUT_LOAD='(1.0,-1.0)';
      PINUSE='BI';
    'GND11':
      PIN_NUMBER='(B21)';
      PINUSE='GROUND';
      NO_LOAD_CHECK='Both';
      NO_IO_CHECK='Both';
      NO_ASSERT_CHECK='TRUE';
      NO_DIR_CHECK='TRUE';
      ALLOW_CONNECT='TRUE';
    'GND12':
      PIN_NUMBER='(B22)';
      PINUSE='GROUND';
      NO_LOAD_CHECK='Both';
      NO_IO_CHECK='Both';
      NO_ASSERT_CHECK='TRUE';
      NO_DIR_CHECK='TRUE';
      ALLOW_CONNECT='TRUE';
    'PETP2':
      PIN_NUMBER='(B23)';
      OUTPUT_TYPE='(TS,TS)';
      BIDIRECTIONAL='TRUE';
      INPUT_LOAD='(-0.01,0.01)';
      OUTPUT_LOAD='(1.0,-1.0)';
      PINUSE='BI';
    'PETN2':
      PIN_NUMBER='(B24)';
      OUTPUT_TYPE='(TS,TS)';
      BIDIRECTIONAL='TRUE';
      INPUT_LOAD='(-0.01,0.01)';
      OUTPUT_LOAD='(1.0,-1.0)';
      PINUSE='BI';
    'GND15':
      PIN_NUMBER='(B25)';
      PINUSE='GROUND';
      NO_LOAD_CHECK='Both';
      NO_IO_CHECK='Both';
      NO_ASSERT_CHECK='TRUE';
      NO_DIR_CHECK='TRUE';
      ALLOW_CONNECT='TRUE';
    'GND17':
      PIN_NUMBER='(B26)';
      PINUSE='GROUND';
      NO_LOAD_CHECK='Both';
      NO_IO_CHECK='Both';
      NO_ASSERT_CHECK='TRUE';
      NO_DIR_CHECK='TRUE';
      ALLOW_CONNECT='TRUE';
    'PETP3':
      PIN_NUMBER='(B27)';
      OUTPUT_TYPE='(TS,TS)';
      BIDIRECTIONAL='TRUE';
      INPUT_LOAD='(-0.01,0.01)';
      OUTPUT_LOAD='(1.0,-1.0)';
      PINUSE='BI';
    'PETN3':
      PIN_NUMBER='(B28)';
      OUTPUT_TYPE='(TS,TS)';
      BIDIRECTIONAL='TRUE';
      INPUT_LOAD='(-0.01,0.01)';
      OUTPUT_LOAD='(1.0,-1.0)';
      PINUSE='BI';
    'GND20':
      PIN_NUMBER='(B29)';
      PINUSE='GROUND';
      NO_LOAD_CHECK='Both';
      NO_IO_CHECK='Both';
      NO_ASSERT_CHECK='TRUE';
      NO_DIR_CHECK='TRUE';
      ALLOW_CONNECT='TRUE';
    'RSVD3':
      PIN_NUMBER='(B30)';
      OUTPUT_TYPE='(TS,TS)';
      BIDIRECTIONAL='TRUE';
      INPUT_LOAD='(-0.01,0.01)';
      OUTPUT_LOAD='(1.0,-1.0)';
      PINUSE='BI';
    'PRSNT2_2*':
      PIN_NUMBER='(B31)';
      OUTPUT_TYPE='(TS,TS)';
      BIDIRECTIONAL='TRUE';
      INPUT_LOAD='(-0.01,0.01)';
      OUTPUT_LOAD='(1.0,-1.0)';
      PINUSE='BI';
    'GND22':
      PIN_NUMBER='(B32)';
      PINUSE='GROUND';
      NO_LOAD_CHECK='Both';
      NO_IO_CHECK='Both';
      NO_ASSERT_CHECK='TRUE';
      NO_DIR_CHECK='TRUE';
      ALLOW_CONNECT='TRUE';
    'PRSNT1*':
      PIN_NUMBER='(A1)';
      OUTPUT_TYPE='(TS,TS)';
      BIDIRECTIONAL='TRUE';
      INPUT_LOAD='(-0.01,0.01)';
      OUTPUT_LOAD='(1.0,-1.0)';
      PINUSE='BI';
    'P_12V3':
      PIN_NUMBER='(A2)';
      PINUSE='POWER';
      NO_LOAD_CHECK='Both';
      NO_IO_CHECK='Both';
      NO_ASSERT_CHECK='TRUE';
      NO_DIR_CHECK='TRUE';
      ALLOW_CONNECT='TRUE';
    'P_12V5':
      PIN_NUMBER='(A3)';
      PINUSE='POWER';
      NO_LOAD_CHECK='Both';
      NO_IO_CHECK='Both';
      NO_ASSERT_CHECK='TRUE';
      NO_DIR_CHECK='TRUE';
      ALLOW_CONNECT='TRUE';
    'GND2':
      PIN_NUMBER='(A4)';
      PINUSE='GROUND';
      NO_LOAD_CHECK='Both';
      NO_IO_CHECK='Both';
      NO_ASSERT_CHECK='TRUE';
      NO_DIR_CHECK='TRUE';
      ALLOW_CONNECT='TRUE';
    'JTAG2':
      PIN_NUMBER='(A5)';
      OUTPUT_TYPE='(TS,TS)';
      BIDIRECTIONAL='TRUE';
      INPUT_LOAD='(-0.01,0.01)';
      OUTPUT_LOAD='(1.0,-1.0)';
      PINUSE='BI';
    'JTAG3':
      PIN_NUMBER='(A6)';
      OUTPUT_TYPE='(TS,TS)';
      BIDIRECTIONAL='TRUE';
      INPUT_LOAD='(-0.01,0.01)';
      OUTPUT_LOAD='(1.0,-1.0)';
      PINUSE='BI';
    'JTAG4':
      PIN_NUMBER='(A7)';
      OUTPUT_TYPE='(TS,TS)';
      BIDIRECTIONAL='TRUE';
      INPUT_LOAD='(-0.01,0.01)';
      OUTPUT_LOAD='(1.0,-1.0)';
      PINUSE='BI';
    'JTAG5':
      PIN_NUMBER='(A8)';
      OUTPUT_TYPE='(TS,TS)';
      BIDIRECTIONAL='TRUE';
      INPUT_LOAD='(-0.01,0.01)';
      OUTPUT_LOAD='(1.0,-1.0)';
      PINUSE='BI';
    'P_3V3_2':
      PIN_NUMBER='(A9)';
      PINUSE='POWER';
      NO_LOAD_CHECK='Both';
      NO_IO_CHECK='Both';
      NO_ASSERT_CHECK='TRUE';
      NO_DIR_CHECK='TRUE';
      ALLOW_CONNECT='TRUE';
    'P_3V3_3':
      PIN_NUMBER='(A10)';
      PINUSE='POWER';
      NO_LOAD_CHECK='Both';
      NO_IO_CHECK='Both';
      NO_ASSERT_CHECK='TRUE';
      NO_DIR_CHECK='TRUE';
      ALLOW_CONNECT='TRUE';
    'PERST*':
      PIN_NUMBER='(A11)';
      OUTPUT_TYPE='(TS,TS)';
      BIDIRECTIONAL='TRUE';
      INPUT_LOAD='(-0.01,0.01)';
      OUTPUT_LOAD='(1.0,-1.0)';
      PINUSE='BI';
    'GND4':
      PIN_NUMBER='(A12)';
      PINUSE='GROUND';
      NO_LOAD_CHECK='Both';
      NO_IO_CHECK='Both';
      NO_ASSERT_CHECK='TRUE';
      NO_DIR_CHECK='TRUE';
      ALLOW_CONNECT='TRUE';
    'REFCLK_P':
      PIN_NUMBER='(A13)';
      OUTPUT_TYPE='(TS,TS)';
      BIDIRECTIONAL='TRUE';
      INPUT_LOAD='(-0.01,0.01)';
      OUTPUT_LOAD='(1.0,-1.0)';
      PINUSE='BI';
    'REFCLK_N':
      PIN_NUMBER='(A14)';
      OUTPUT_TYPE='(TS,TS)';
      BIDIRECTIONAL='TRUE';
      INPUT_LOAD='(-0.01,0.01)';
      OUTPUT_LOAD='(1.0,-1.0)';
      PINUSE='BI';
    'GND6':
      PIN_NUMBER='(A15)';
      PINUSE='GROUND';
      NO_LOAD_CHECK='Both';
      NO_IO_CHECK='Both';
      NO_ASSERT_CHECK='TRUE';
      NO_DIR_CHECK='TRUE';
      ALLOW_CONNECT='TRUE';
    'PERP0':
      PIN_NUMBER='(A16)';
      OUTPUT_TYPE='(TS,TS)';
      BIDIRECTIONAL='TRUE';
      INPUT_LOAD='(-0.01,0.01)';
      OUTPUT_LOAD='(1.0,-1.0)';
      PINUSE='BI';
    'PERN0':
      PIN_NUMBER='(A17)';
      OUTPUT_TYPE='(TS,TS)';
      BIDIRECTIONAL='TRUE';
      INPUT_LOAD='(-0.01,0.01)';
      OUTPUT_LOAD='(1.0,-1.0)';
      PINUSE='BI';
    'GND8':
      PIN_NUMBER='(A18)';
      PINUSE='GROUND';
      NO_LOAD_CHECK='Both';
      NO_IO_CHECK='Both';
      NO_ASSERT_CHECK='TRUE';
      NO_DIR_CHECK='TRUE';
      ALLOW_CONNECT='TRUE';
    'RSVD2':
      PIN_NUMBER='(A19)';
      OUTPUT_TYPE='(TS,TS)';
      BIDIRECTIONAL='TRUE';
      INPUT_LOAD='(-0.01,0.01)';
      OUTPUT_LOAD='(1.0,-1.0)';
      PINUSE='BI';
    'GND10':
      PIN_NUMBER='(A20)';
      PINUSE='GROUND';
      NO_LOAD_CHECK='Both';
      NO_IO_CHECK='Both';
      NO_ASSERT_CHECK='TRUE';
      NO_DIR_CHECK='TRUE';
      ALLOW_CONNECT='TRUE';
    'PERP1':
      PIN_NUMBER='(A21)';
      OUTPUT_TYPE='(TS,TS)';
      BIDIRECTIONAL='TRUE';
      INPUT_LOAD='(-0.01,0.01)';
      OUTPUT_LOAD='(1.0,-1.0)';
      PINUSE='BI';
    'PERN1':
      PIN_NUMBER='(A22)';
      OUTPUT_TYPE='(TS,TS)';
      BIDIRECTIONAL='TRUE';
      INPUT_LOAD='(-0.01,0.01)';
      OUTPUT_LOAD='(1.0,-1.0)';
      PINUSE='BI';
    'GND13':
      PIN_NUMBER='(A23)';
      PINUSE='GROUND';
      NO_LOAD_CHECK='Both';
      NO_IO_CHECK='Both';
      NO_ASSERT_CHECK='TRUE';
      NO_DIR_CHECK='TRUE';
      ALLOW_CONNECT='TRUE';
    'GND14':
      PIN_NUMBER='(A24)';
      PINUSE='GROUND';
      NO_LOAD_CHECK='Both';
      NO_IO_CHECK='Both';
      NO_ASSERT_CHECK='TRUE';
      NO_DIR_CHECK='TRUE';
      ALLOW_CONNECT='TRUE';
    'PERP2':
      PIN_NUMBER='(A25)';
      OUTPUT_TYPE='(TS,TS)';
      BIDIRECTIONAL='TRUE';
      INPUT_LOAD='(-0.01,0.01)';
      OUTPUT_LOAD='(1.0,-1.0)';
      PINUSE='BI';
    'PERN2':
      PIN_NUMBER='(A26)';
      OUTPUT_TYPE='(TS,TS)';
      BIDIRECTIONAL='TRUE';
      INPUT_LOAD='(-0.01,0.01)';
      OUTPUT_LOAD='(1.0,-1.0)';
      PINUSE='BI';
    'GND18':
      PIN_NUMBER='(A27)';
      PINUSE='GROUND';
      NO_LOAD_CHECK='Both';
      NO_IO_CHECK='Both';
      NO_ASSERT_CHECK='TRUE';
      NO_DIR_CHECK='TRUE';
      ALLOW_CONNECT='TRUE';
    'GND19':
      PIN_NUMBER='(A28)';
      PINUSE='GROUND';
      NO_LOAD_CHECK='Both';
      NO_IO_CHECK='Both';
      NO_ASSERT_CHECK='TRUE';
      NO_DIR_CHECK='TRUE';
      ALLOW_CONNECT='TRUE';
    'PERP3':
      PIN_NUMBER='(A29)';
      OUTPUT_TYPE='(TS,TS)';
      BIDIRECTIONAL='TRUE';
      INPUT_LOAD='(-0.01,0.01)';
      OUTPUT_LOAD='(1.0,-1.0)';
      PINUSE='BI';
    'PERN3':
      PIN_NUMBER='(A30)';
      OUTPUT_TYPE='(TS,TS)';
      BIDIRECTIONAL='TRUE';
      INPUT_LOAD='(-0.01,0.01)';
      OUTPUT_LOAD='(1.0,-1.0)';
      PINUSE='BI';
    'GND21':
      PIN_NUMBER='(A31)';
      PINUSE='GROUND';
      NO_LOAD_CHECK='Both';
      NO_IO_CHECK='Both';
      NO_ASSERT_CHECK='TRUE';
      NO_DIR_CHECK='TRUE';
      ALLOW_CONNECT='TRUE';
    'RSVD4':
      PIN_NUMBER='(A32)';
      OUTPUT_TYPE='(TS,TS)';
      BIDIRECTIONAL='TRUE';
      INPUT_LOAD='(-0.01,0.01)';
      OUTPUT_LOAD='(1.0,-1.0)';
      PINUSE='BI';
  end_pin;
  body
      PART_NAME='CONN_64P_GF';
      BODY_NAME='CONN_64P_GF';
      PHYS_DES_PREFIX='GF';
      CLASS='IO';
      JEDEC_TYPE='S_M_EF64_PCIE_P0394_V1';
      ALT_SYMBOLS='(S_M_EF64_PCIE_P0394_V1)';
      DESCRIPTION='GOLDEN FINGER FOR MPN 10061913-101TLF,64PIN';
      PARENT_PART_TYPE='CONN_64P_GF';
      PARENT_PPT='CONN_64P_GF';
      PARENT_PPT_PART='CONN_64P_GF-S_M_EF64_PCIE_P0394_V1';
  end_body;
end_primitive;
primitive 'CONN_HDR_1X3_M_S_SMT-G205-1002A';
  pin
    '1':
      PIN_NUMBER='(1)';
      OUTPUT_TYPE='(TS,TS)';
      BIDIRECTIONAL='TRUE';
      INPUT_LOAD='(-0.01,0.01)';
      OUTPUT_LOAD='(1.0,-1.0)';
      PINUSE='BI';
    '2':
      PIN_NUMBER='(2)';
      OUTPUT_TYPE='(TS,TS)';
      BIDIRECTIONAL='TRUE';
      INPUT_LOAD='(-0.01,0.01)';
      OUTPUT_LOAD='(1.0,-1.0)';
      PINUSE='BI';
    '3':
      PIN_NUMBER='(3)';
      OUTPUT_TYPE='(TS,TS)';
      BIDIRECTIONAL='TRUE';
      INPUT_LOAD='(-0.01,0.01)';
      OUTPUT_LOAD='(1.0,-1.0)';
      PINUSE='BI';
  end_pin;
  body
      PART_NAME='CONN_HDR_1X3_M_S_SMT';
      BODY_NAME='CONN_HDR_1X3_M_S_SMT';
      PHYS_DES_PREFIX='J';
      CLASS='IO';
      JEDEC_TYPE='S_M_H_3P_S_P058';
      ALT_SYMBOLS='(S_M_H_3P_S_P058)';
      DESCRIPTION='CON,RF,MINI-SMA,50OHM';
      CPN_STATUS='';
      PARENT_PART_TYPE='CONN_HDR_1X3_M_S_SMT';
      PARENT_PPT='CONN_HDR_1X3_M_S_SMT';
      PARENT_PPT_PART='CONN_HDR_1X3_M_S_SMT-G205-10020-01';
  end_body;
end_primitive;
primitive 'CONN_HDR_2X10_M_S_SMT-G200-130A';
  pin
    '1':
      PIN_NUMBER='(1)';
      OUTPUT_TYPE='(TS,TS)';
      BIDIRECTIONAL='TRUE';
      INPUT_LOAD='(-0.01,0.01)';
      OUTPUT_LOAD='(1.0,-1.0)';
      PINUSE='BI';
    '3':
      PIN_NUMBER='(3)';
      OUTPUT_TYPE='(TS,TS)';
      BIDIRECTIONAL='TRUE';
      INPUT_LOAD='(-0.01,0.01)';
      OUTPUT_LOAD='(1.0,-1.0)';
      PINUSE='BI';
    '5':
      PIN_NUMBER='(5)';
      OUTPUT_TYPE='(TS,TS)';
      BIDIRECTIONAL='TRUE';
      INPUT_LOAD='(-0.01,0.01)';
      OUTPUT_LOAD='(1.0,-1.0)';
      PINUSE='BI';
    '7':
      PIN_NUMBER='(7)';
      OUTPUT_TYPE='(TS,TS)';
      BIDIRECTIONAL='TRUE';
      INPUT_LOAD='(-0.01,0.01)';
      OUTPUT_LOAD='(1.0,-1.0)';
      PINUSE='BI';
    '9':
      PIN_NUMBER='(9)';
      OUTPUT_TYPE='(TS,TS)';
      BIDIRECTIONAL='TRUE';
      INPUT_LOAD='(-0.01,0.01)';
      OUTPUT_LOAD='(1.0,-1.0)';
      PINUSE='BI';
    '11':
      PIN_NUMBER='(11)';
      OUTPUT_TYPE='(TS,TS)';
      BIDIRECTIONAL='TRUE';
      INPUT_LOAD='(-0.01,0.01)';
      OUTPUT_LOAD='(1.0,-1.0)';
      PINUSE='BI';
    '13':
      PIN_NUMBER='(13)';
      OUTPUT_TYPE='(TS,TS)';
      BIDIRECTIONAL='TRUE';
      INPUT_LOAD='(-0.01,0.01)';
      OUTPUT_LOAD='(1.0,-1.0)';
      PINUSE='BI';
    '15':
      PIN_NUMBER='(15)';
      OUTPUT_TYPE='(TS,TS)';
      BIDIRECTIONAL='TRUE';
      INPUT_LOAD='(-0.01,0.01)';
      OUTPUT_LOAD='(1.0,-1.0)';
      PINUSE='BI';
    '17':
      PIN_NUMBER='(17)';
      OUTPUT_TYPE='(TS,TS)';
      BIDIRECTIONAL='TRUE';
      INPUT_LOAD='(-0.01,0.01)';
      OUTPUT_LOAD='(1.0,-1.0)';
      PINUSE='BI';
    '19':
      PIN_NUMBER='(19)';
      OUTPUT_TYPE='(TS,TS)';
      BIDIRECTIONAL='TRUE';
      INPUT_LOAD='(-0.01,0.01)';
      OUTPUT_LOAD='(1.0,-1.0)';
      PINUSE='BI';
    '2':
      PIN_NUMBER='(2)';
      OUTPUT_TYPE='(TS,TS)';
      BIDIRECTIONAL='TRUE';
      INPUT_LOAD='(-0.01,0.01)';
      OUTPUT_LOAD='(1.0,-1.0)';
      PINUSE='BI';
    '4':
      PIN_NUMBER='(4)';
      OUTPUT_TYPE='(TS,TS)';
      BIDIRECTIONAL='TRUE';
      INPUT_LOAD='(-0.01,0.01)';
      OUTPUT_LOAD='(1.0,-1.0)';
      PINUSE='BI';
    '6':
      PIN_NUMBER='(6)';
      OUTPUT_TYPE='(TS,TS)';
      BIDIRECTIONAL='TRUE';
      INPUT_LOAD='(-0.01,0.01)';
      OUTPUT_LOAD='(1.0,-1.0)';
      PINUSE='BI';
    '8':
      PIN_NUMBER='(8)';
      OUTPUT_TYPE='(TS,TS)';
      BIDIRECTIONAL='TRUE';
      INPUT_LOAD='(-0.01,0.01)';
      OUTPUT_LOAD='(1.0,-1.0)';
      PINUSE='BI';
    '10':
      PIN_NUMBER='(10)';
      OUTPUT_TYPE='(TS,TS)';
      BIDIRECTIONAL='TRUE';
      INPUT_LOAD='(-0.01,0.01)';
      OUTPUT_LOAD='(1.0,-1.0)';
      PINUSE='BI';
    '12':
      PIN_NUMBER='(12)';
      OUTPUT_TYPE='(TS,TS)';
      BIDIRECTIONAL='TRUE';
      INPUT_LOAD='(-0.01,0.01)';
      OUTPUT_LOAD='(1.0,-1.0)';
      PINUSE='BI';
    '14':
      PIN_NUMBER='(14)';
      OUTPUT_TYPE='(TS,TS)';
      BIDIRECTIONAL='TRUE';
      INPUT_LOAD='(-0.01,0.01)';
      OUTPUT_LOAD='(1.0,-1.0)';
      PINUSE='BI';
    '16':
      PIN_NUMBER='(16)';
      OUTPUT_TYPE='(TS,TS)';
      BIDIRECTIONAL='TRUE';
      INPUT_LOAD='(-0.01,0.01)';
      OUTPUT_LOAD='(1.0,-1.0)';
      PINUSE='BI';
    '18':
      PIN_NUMBER='(18)';
      OUTPUT_TYPE='(TS,TS)';
      BIDIRECTIONAL='TRUE';
      INPUT_LOAD='(-0.01,0.01)';
      OUTPUT_LOAD='(1.0,-1.0)';
      PINUSE='BI';
    '20':
      PIN_NUMBER='(20)';
      OUTPUT_TYPE='(TS,TS)';
      BIDIRECTIONAL='TRUE';
      INPUT_LOAD='(-0.01,0.01)';
      OUTPUT_LOAD='(1.0,-1.0)';
      PINUSE='BI';
  end_pin;
  body
      PART_NAME='CONN_HDR_2X10_M_S_SMT';
      BODY_NAME='CONN_HDR_2X10_M_S_SMT';
      PHYS_DES_PREFIX='J';
      CLASS='IO';
      JEDEC_TYPE='S_M_H_2X10_S_P0197';
      ALT_SYMBOLS='(S_M_H_2X10_S_P0197)';
      DESCRIPTION='CON,20 PINS,2X10,0.5MM PITCH,RECEPTACLE,FPC,VERT,WHITE,SMT';
      CPN_STATUS='';
      PARENT_PART_TYPE='CONN_HDR_2X10_M_S_SMT';
      PARENT_PPT='CONN_HDR_2X10_M_S_SMT';
      PARENT_PPT_PART='CONN_HDR_2X10_M_S_SMT-G200-13077-01';
  end_body;
end_primitive;
primitive 'CONN_HDR_2X2_M_S_SMT-G200-1068A';
  pin
    '1':
      PIN_NUMBER='(1)';
      OUTPUT_TYPE='(TS,TS)';
      BIDIRECTIONAL='TRUE';
      INPUT_LOAD='(-0.01,0.01)';
      OUTPUT_LOAD='(1.0,-1.0)';
      PINUSE='BI';
    '2':
      PIN_NUMBER='(2)';
      OUTPUT_TYPE='(TS,TS)';
      BIDIRECTIONAL='TRUE';
      INPUT_LOAD='(-0.01,0.01)';
      OUTPUT_LOAD='(1.0,-1.0)';
      PINUSE='BI';
    '3':
      PIN_NUMBER='(3)';
      OUTPUT_TYPE='(TS,TS)';
      BIDIRECTIONAL='TRUE';
      INPUT_LOAD='(-0.01,0.01)';
      OUTPUT_LOAD='(1.0,-1.0)';
      PINUSE='BI';
    '4':
      PIN_NUMBER='(4)';
      OUTPUT_TYPE='(TS,TS)';
      BIDIRECTIONAL='TRUE';
      INPUT_LOAD='(-0.01,0.01)';
      OUTPUT_LOAD='(1.0,-1.0)';
      PINUSE='BI';
  end_pin;
  body
      PART_NAME='CONN_HDR_2X2_M_S_SMT';
      BODY_NAME='CONN_HDR_2X2_M_S_SMT';
      PHYS_DES_PREFIX='J';
      CLASS='IO';
      JEDEC_TYPE='S_M_H_2X2_S_P100_V3';
      ALT_SYMBOLS='(S_M_H_2X2_S_P100_V3)';
      DESCRIPTION='CON, HEADER, 4PIN, 2 X 2 DUAL ROHS, 2.54MM PITCH, SMT';
      PARENT_PART_TYPE='CONN_HDR_2X2_M_S_SMT';
      PARENT_PPT='CONN_HDR_2X2_M_S_SMT';
      PARENT_PPT_PART='CONN_HDR_2X2_M_S_SMT-G200-10686-01';
  end_body;
end_primitive;
primitive 'CONN_HDR_2X3_M_RA_TH-G200-1251A';
  pin
    '1':
      PIN_NUMBER='(1)';
      OUTPUT_TYPE='(TS,TS)';
      BIDIRECTIONAL='TRUE';
      INPUT_LOAD='(-0.01,0.01)';
      OUTPUT_LOAD='(1.0,-1.0)';
      PINUSE='BI';
    '2':
      PIN_NUMBER='(2)';
      OUTPUT_TYPE='(TS,TS)';
      BIDIRECTIONAL='TRUE';
      INPUT_LOAD='(-0.01,0.01)';
      OUTPUT_LOAD='(1.0,-1.0)';
      PINUSE='BI';
    '3':
      PIN_NUMBER='(3)';
      OUTPUT_TYPE='(TS,TS)';
      BIDIRECTIONAL='TRUE';
      INPUT_LOAD='(-0.01,0.01)';
      OUTPUT_LOAD='(1.0,-1.0)';
      PINUSE='BI';
    '4':
      PIN_NUMBER='(4)';
      OUTPUT_TYPE='(TS,TS)';
      BIDIRECTIONAL='TRUE';
      INPUT_LOAD='(-0.01,0.01)';
      OUTPUT_LOAD='(1.0,-1.0)';
      PINUSE='BI';
    '5':
      PIN_NUMBER='(5)';
      OUTPUT_TYPE='(TS,TS)';
      BIDIRECTIONAL='TRUE';
      INPUT_LOAD='(-0.01,0.01)';
      OUTPUT_LOAD='(1.0,-1.0)';
      PINUSE='BI';
    '6':
      PIN_NUMBER='(6)';
      OUTPUT_TYPE='(TS,TS)';
      BIDIRECTIONAL='TRUE';
      INPUT_LOAD='(-0.01,0.01)';
      OUTPUT_LOAD='(1.0,-1.0)';
      PINUSE='BI';
  end_pin;
  body
      PART_NAME='CONN_HDR_2X3_M_RA_TH';
      BODY_NAME='CONN_HDR_2X3_M_RA_TH';
      PHYS_DES_PREFIX='J';
      CLASS='IO';
      JEDEC_TYPE='P_M_H_2X3_NP2_RA_P165_V1';
      ALT_SYMBOLS='(P_M_H_2X3_NP2_RA_P165_V1)';
      DESCRIPTION='CON, 6P, 2X3, 4.2X4.2MM PITCH, R/A, BLACK, TH';
      PARENT_PART_TYPE='CONN_HDR_2X3_M_RA_TH';
      PARENT_PPT='CONN_HDR_2X3_M_RA_TH';
      PARENT_PPT_PART='CONN_HDR_2X3_M_RA_TH-G200-12517-01';
  end_body;
end_primitive;
primitive 'CONN_HDR_2X4_F_S_SMT-G200-1307A';
  pin
    '1':
      PIN_NUMBER='(1)';
      OUTPUT_TYPE='(TS,TS)';
      BIDIRECTIONAL='TRUE';
      INPUT_LOAD='(-0.01,0.01)';
      OUTPUT_LOAD='(1.0,-1.0)';
      PINUSE='BI';
    '2':
      PIN_NUMBER='(2)';
      OUTPUT_TYPE='(TS,TS)';
      BIDIRECTIONAL='TRUE';
      INPUT_LOAD='(-0.01,0.01)';
      OUTPUT_LOAD='(1.0,-1.0)';
      PINUSE='BI';
    '3':
      PIN_NUMBER='(3)';
      OUTPUT_TYPE='(TS,TS)';
      BIDIRECTIONAL='TRUE';
      INPUT_LOAD='(-0.01,0.01)';
      OUTPUT_LOAD='(1.0,-1.0)';
      PINUSE='BI';
    '4':
      PIN_NUMBER='(4)';
      OUTPUT_TYPE='(TS,TS)';
      BIDIRECTIONAL='TRUE';
      INPUT_LOAD='(-0.01,0.01)';
      OUTPUT_LOAD='(1.0,-1.0)';
      PINUSE='BI';
    '5':
      PIN_NUMBER='(5)';
      OUTPUT_TYPE='(TS,TS)';
      BIDIRECTIONAL='TRUE';
      INPUT_LOAD='(-0.01,0.01)';
      OUTPUT_LOAD='(1.0,-1.0)';
      PINUSE='BI';
    '6':
      PIN_NUMBER='(6)';
      OUTPUT_TYPE='(TS,TS)';
      BIDIRECTIONAL='TRUE';
      INPUT_LOAD='(-0.01,0.01)';
      OUTPUT_LOAD='(1.0,-1.0)';
      PINUSE='BI';
    '7':
      PIN_NUMBER='(7)';
      OUTPUT_TYPE='(TS,TS)';
      BIDIRECTIONAL='TRUE';
      INPUT_LOAD='(-0.01,0.01)';
      OUTPUT_LOAD='(1.0,-1.0)';
      PINUSE='BI';
    '8':
      PIN_NUMBER='(8)';
      OUTPUT_TYPE='(TS,TS)';
      BIDIRECTIONAL='TRUE';
      INPUT_LOAD='(-0.01,0.01)';
      OUTPUT_LOAD='(1.0,-1.0)';
      PINUSE='BI';
  end_pin;
  body
      PART_NAME='CONN_HDR_2X4_F_S_SMT';
      BODY_NAME='CONN_HDR_2X4_F_S_SMT';
      PHYS_DES_PREFIX='J';
      CLASS='IO';
      JEDEC_TYPE='S_F_H_2X4_S_P0787_V1';
      ALT_SYMBOLS='(S_F_H_2X4_S_P0787_V1)';
      DESCRIPTION='CON,8P,2X4,SOCKET,2MM PITCH,VT,SMT';
      CPN_STATUS='';
      PARENT_PART_TYPE='CONN_HDR_2X4_F_S_SMT';
      PARENT_PPT='CONN_HDR_2X4_F_S_SMT';
      PARENT_PPT_PART='CONN_HDR_2X4_F_S_SMT-G200-13079-01';
  end_body;
end_primitive;
primitive 'CONN_HDR_2X6_F_S_SMT-G200-1313A';
  pin
    '1':
      PIN_NUMBER='(1)';
      OUTPUT_TYPE='(TS,TS)';
      BIDIRECTIONAL='TRUE';
      INPUT_LOAD='(-0.01,0.01)';
      OUTPUT_LOAD='(1.0,-1.0)';
      PINUSE='BI';
    '3':
      PIN_NUMBER='(3)';
      OUTPUT_TYPE='(TS,TS)';
      BIDIRECTIONAL='TRUE';
      INPUT_LOAD='(-0.01,0.01)';
      OUTPUT_LOAD='(1.0,-1.0)';
      PINUSE='BI';
    '5':
      PIN_NUMBER='(5)';
      OUTPUT_TYPE='(TS,TS)';
      BIDIRECTIONAL='TRUE';
      INPUT_LOAD='(-0.01,0.01)';
      OUTPUT_LOAD='(1.0,-1.0)';
      PINUSE='BI';
    '7':
      PIN_NUMBER='(7)';
      OUTPUT_TYPE='(TS,TS)';
      BIDIRECTIONAL='TRUE';
      INPUT_LOAD='(-0.01,0.01)';
      OUTPUT_LOAD='(1.0,-1.0)';
      PINUSE='BI';
    '9':
      PIN_NUMBER='(9)';
      OUTPUT_TYPE='(TS,TS)';
      BIDIRECTIONAL='TRUE';
      INPUT_LOAD='(-0.01,0.01)';
      OUTPUT_LOAD='(1.0,-1.0)';
      PINUSE='BI';
    '11':
      PIN_NUMBER='(11)';
      OUTPUT_TYPE='(TS,TS)';
      BIDIRECTIONAL='TRUE';
      INPUT_LOAD='(-0.01,0.01)';
      OUTPUT_LOAD='(1.0,-1.0)';
      PINUSE='BI';
    '2':
      PIN_NUMBER='(2)';
      OUTPUT_TYPE='(TS,TS)';
      BIDIRECTIONAL='TRUE';
      INPUT_LOAD='(-0.01,0.01)';
      OUTPUT_LOAD='(1.0,-1.0)';
      PINUSE='BI';
    '4':
      PIN_NUMBER='(4)';
      OUTPUT_TYPE='(TS,TS)';
      BIDIRECTIONAL='TRUE';
      INPUT_LOAD='(-0.01,0.01)';
      OUTPUT_LOAD='(1.0,-1.0)';
      PINUSE='BI';
    '6':
      PIN_NUMBER='(6)';
      OUTPUT_TYPE='(TS,TS)';
      BIDIRECTIONAL='TRUE';
      INPUT_LOAD='(-0.01,0.01)';
      OUTPUT_LOAD='(1.0,-1.0)';
      PINUSE='BI';
    '8':
      PIN_NUMBER='(8)';
      OUTPUT_TYPE='(TS,TS)';
      BIDIRECTIONAL='TRUE';
      INPUT_LOAD='(-0.01,0.01)';
      OUTPUT_LOAD='(1.0,-1.0)';
      PINUSE='BI';
    '10':
      PIN_NUMBER='(10)';
      OUTPUT_TYPE='(TS,TS)';
      BIDIRECTIONAL='TRUE';
      INPUT_LOAD='(-0.01,0.01)';
      OUTPUT_LOAD='(1.0,-1.0)';
      PINUSE='BI';
    '12':
      PIN_NUMBER='(12)';
      OUTPUT_TYPE='(TS,TS)';
      BIDIRECTIONAL='TRUE';
      INPUT_LOAD='(-0.01,0.01)';
      OUTPUT_LOAD='(1.0,-1.0)';
      PINUSE='BI';
  end_pin;
  body
      PART_NAME='CONN_HDR_2X6_F_S_SMT';
      BODY_NAME='CONN_HDR_2X6_F_S_SMT';
      PHYS_DES_PREFIX='J';
      CLASS='IO';
      JEDEC_TYPE='S_F_H_2X6_RA_P100';
      ALT_SYMBOLS='(S_F_H_2X6_RA_P100)';
      DESCRIPTION='CON,12P,2X6,RCPT DOUBLE ROW,2.54MM,SMT,R/A';
      CPN_STATUS='';
      PARENT_PART_TYPE='CONN_HDR_2X6_F_S_SMT';
      PARENT_PPT='CONN_HDR_2X6_F_S_SMT';
      PARENT_PPT_PART='CONN_HDR_2X6_F_S_SMT-G200-13133-01,SMH-106-02-L-D-TR';
  end_body;
end_primitive;
primitive 'CONN_JACK_1P_GH4_S_TH-G200-130A';
  pin
    '1':
      PIN_NUMBER='(1)';
      OUTPUT_TYPE='(TS,TS)';
      BIDIRECTIONAL='TRUE';
      INPUT_LOAD='(-0.01,0.01)';
      OUTPUT_LOAD='(1.0,-1.0)';
      PINUSE='BI';
    'GH1':
      PIN_NUMBER='(GH1)';
      OUTPUT_TYPE='(TS,TS)';
      BIDIRECTIONAL='TRUE';
      INPUT_LOAD='(-0.01,0.01)';
      OUTPUT_LOAD='(1.0,-1.0)';
      PINUSE='BI';
    'GH2':
      PIN_NUMBER='(GH2)';
      OUTPUT_TYPE='(TS,TS)';
      BIDIRECTIONAL='TRUE';
      INPUT_LOAD='(-0.01,0.01)';
      OUTPUT_LOAD='(1.0,-1.0)';
      PINUSE='BI';
    'GH3':
      PIN_NUMBER='(GH3)';
      OUTPUT_TYPE='(TS,TS)';
      BIDIRECTIONAL='TRUE';
      INPUT_LOAD='(-0.01,0.01)';
      OUTPUT_LOAD='(1.0,-1.0)';
      PINUSE='BI';
    'GH4':
      PIN_NUMBER='(GH4)';
      OUTPUT_TYPE='(TS,TS)';
      BIDIRECTIONAL='TRUE';
      INPUT_LOAD='(-0.01,0.01)';
      OUTPUT_LOAD='(1.0,-1.0)';
      PINUSE='BI';
  end_pin;
  body
      PART_NAME='CONN_JACK_1P_GH4_S_TH';
      BODY_NAME='CONN_JACK_1P_GH4_S_TH';
      PHYS_DES_PREFIX='J';
      CLASS='IO';
      JEDEC_TYPE='P_F_JACK_1P_GH4_RA_P200';
      ALT_SYMBOLS='(P_F_JACK_1P_GH4_RA_P200)';
      DESCRIPTION='CON,SMA JACK,50 OHM,RA,SMT';
      CPN_STATUS='';
      PARENT_PART_TYPE='CONN_JACK_1P_GH4_S_TH';
      PARENT_PPT='CONN_JACK_1P_GH4_S_TH';
      PARENT_PPT_PART='CONN_JACK_1P_GH4_S_TH-G200-13091-01,2081680-1';
  end_body;
end_primitive;
primitive 'CONN_USB_14P_GH4_F_RA_TH-G200-A';
  pin
    'GND_1':
      PIN_NUMBER='(A1)';
      PINUSE='GROUND';
      NO_LOAD_CHECK='Both';
      NO_IO_CHECK='Both';
      NO_ASSERT_CHECK='TRUE';
      NO_DIR_CHECK='TRUE';
      ALLOW_CONNECT='TRUE';
    'VBUS_1':
      PIN_NUMBER='(A4)';
      PINUSE='POWER';
      NO_LOAD_CHECK='Both';
      NO_IO_CHECK='Both';
      NO_ASSERT_CHECK='TRUE';
      NO_DIR_CHECK='TRUE';
      ALLOW_CONNECT='TRUE';
    'CC1':
      PIN_NUMBER='(A5)';
      OUTPUT_TYPE='(TS,TS)';
      BIDIRECTIONAL='TRUE';
      INPUT_LOAD='(-0.01,0.01)';
      OUTPUT_LOAD='(1.0,-1.0)';
      PINUSE='BI';
    'D1_P':
      PIN_NUMBER='(A6)';
      OUTPUT_TYPE='(TS,TS)';
      BIDIRECTIONAL='TRUE';
      INPUT_LOAD='(-0.01,0.01)';
      OUTPUT_LOAD='(1.0,-1.0)';
      PINUSE='BI';
    'D1_N':
      PIN_NUMBER='(A7)';
      OUTPUT_TYPE='(TS,TS)';
      BIDIRECTIONAL='TRUE';
      INPUT_LOAD='(-0.01,0.01)';
      OUTPUT_LOAD='(1.0,-1.0)';
      PINUSE='BI';
    'VBUS_2':
      PIN_NUMBER='(A9)';
      PINUSE='POWER';
      NO_LOAD_CHECK='Both';
      NO_IO_CHECK='Both';
      NO_ASSERT_CHECK='TRUE';
      NO_DIR_CHECK='TRUE';
      ALLOW_CONNECT='TRUE';
    'GND_2':
      PIN_NUMBER='(A12)';
      PINUSE='GROUND';
      NO_LOAD_CHECK='Both';
      NO_IO_CHECK='Both';
      NO_ASSERT_CHECK='TRUE';
      NO_DIR_CHECK='TRUE';
      ALLOW_CONNECT='TRUE';
    'GND_3':
      PIN_NUMBER='(B1)';
      PINUSE='GROUND';
      NO_LOAD_CHECK='Both';
      NO_IO_CHECK='Both';
      NO_ASSERT_CHECK='TRUE';
      NO_DIR_CHECK='TRUE';
      ALLOW_CONNECT='TRUE';
    'VBUS_3':
      PIN_NUMBER='(B4)';
      PINUSE='POWER';
      NO_LOAD_CHECK='Both';
      NO_IO_CHECK='Both';
      NO_ASSERT_CHECK='TRUE';
      NO_DIR_CHECK='TRUE';
      ALLOW_CONNECT='TRUE';
    'CC2':
      PIN_NUMBER='(B5)';
      OUTPUT_TYPE='(TS,TS)';
      BIDIRECTIONAL='TRUE';
      INPUT_LOAD='(-0.01,0.01)';
      OUTPUT_LOAD='(1.0,-1.0)';
      PINUSE='BI';
    'D2_P':
      PIN_NUMBER='(B6)';
      OUTPUT_TYPE='(TS,TS)';
      BIDIRECTIONAL='TRUE';
      INPUT_LOAD='(-0.01,0.01)';
      OUTPUT_LOAD='(1.0,-1.0)';
      PINUSE='BI';
    'D2_N':
      PIN_NUMBER='(B7)';
      OUTPUT_TYPE='(TS,TS)';
      BIDIRECTIONAL='TRUE';
      INPUT_LOAD='(-0.01,0.01)';
      OUTPUT_LOAD='(1.0,-1.0)';
      PINUSE='BI';
    'VBUS_4':
      PIN_NUMBER='(B9)';
      PINUSE='POWER';
      NO_LOAD_CHECK='Both';
      NO_IO_CHECK='Both';
      NO_ASSERT_CHECK='TRUE';
      NO_DIR_CHECK='TRUE';
      ALLOW_CONNECT='TRUE';
    'GND_4':
      PIN_NUMBER='(B12)';
      PINUSE='GROUND';
      NO_LOAD_CHECK='Both';
      NO_IO_CHECK='Both';
      NO_ASSERT_CHECK='TRUE';
      NO_DIR_CHECK='TRUE';
      ALLOW_CONNECT='TRUE';
    'GH1':
      PIN_NUMBER='(GH1)';
      PINUSE='GROUND';
      NO_LOAD_CHECK='Both';
      NO_IO_CHECK='Both';
      NO_ASSERT_CHECK='TRUE';
      NO_DIR_CHECK='TRUE';
      ALLOW_CONNECT='TRUE';
    'GH2':
      PIN_NUMBER='(GH2)';
      PINUSE='GROUND';
      NO_LOAD_CHECK='Both';
      NO_IO_CHECK='Both';
      NO_ASSERT_CHECK='TRUE';
      NO_DIR_CHECK='TRUE';
      ALLOW_CONNECT='TRUE';
    'GH3':
      PIN_NUMBER='(GH3)';
      PINUSE='GROUND';
      NO_LOAD_CHECK='Both';
      NO_IO_CHECK='Both';
      NO_ASSERT_CHECK='TRUE';
      NO_DIR_CHECK='TRUE';
      ALLOW_CONNECT='TRUE';
    'GH4':
      PIN_NUMBER='(GH4)';
      PINUSE='GROUND';
      NO_LOAD_CHECK='Both';
      NO_IO_CHECK='Both';
      NO_ASSERT_CHECK='TRUE';
      NO_DIR_CHECK='TRUE';
      ALLOW_CONNECT='TRUE';
  end_pin;
  body
      PART_NAME='CONN_USB_14P_GH4_F_RA_TH';
      BODY_NAME='CONN_USB_14P_GH4_F_RA_TH';
      PHYS_DES_PREFIX='J';
      CLASS='IO';
      JEDEC_TYPE='P_F_USB_2X7_GH4_RA_P035_PIH';
      ALT_SYMBOLS='(P_F_USB_2X7_GH4_RA_P035_PIH)';
      DESCRIPTION='CON,14P,2X7,0.78MM PITCH,RCPT,USB2.0,TYPE C,RA,PIH,TH';
      CPN_STATUS='';
      PARENT_PART_TYPE='CONN_USB_14P_GH4_F_RA_TH';
      PARENT_PPT='CONN_USB_14P_GH4_F_RA_TH';
      PARENT_PPT_PART='CONN_USB_14P_GH4_F_RA_TH-G200-13135-01,2169890002';
  end_body;
end_primitive;
primitive 'CONN_USB_1X5_G2_GH4_F_RA_SMT-GA';
  pin
    '1':
      PIN_NUMBER='(1)';
      OUTPUT_TYPE='(TS,TS)';
      BIDIRECTIONAL='TRUE';
      INPUT_LOAD='(-0.01,0.01)';
      OUTPUT_LOAD='(1.0,-1.0)';
      PINUSE='BI';
    '2':
      PIN_NUMBER='(2)';
      OUTPUT_TYPE='(TS,TS)';
      BIDIRECTIONAL='TRUE';
      INPUT_LOAD='(-0.01,0.01)';
      OUTPUT_LOAD='(1.0,-1.0)';
      PINUSE='BI';
    '3':
      PIN_NUMBER='(3)';
      OUTPUT_TYPE='(TS,TS)';
      BIDIRECTIONAL='TRUE';
      INPUT_LOAD='(-0.01,0.01)';
      OUTPUT_LOAD='(1.0,-1.0)';
      PINUSE='BI';
    '4':
      PIN_NUMBER='(4)';
      OUTPUT_TYPE='(TS,TS)';
      BIDIRECTIONAL='TRUE';
      INPUT_LOAD='(-0.01,0.01)';
      OUTPUT_LOAD='(1.0,-1.0)';
      PINUSE='BI';
    '5':
      PIN_NUMBER='(5)';
      OUTPUT_TYPE='(TS,TS)';
      BIDIRECTIONAL='TRUE';
      INPUT_LOAD='(-0.01,0.01)';
      OUTPUT_LOAD='(1.0,-1.0)';
      PINUSE='BI';
    'G1':
      PIN_NUMBER='(G1)';
      PINUSE='GROUND';
      NO_LOAD_CHECK='Both';
      NO_IO_CHECK='Both';
      NO_ASSERT_CHECK='TRUE';
      NO_DIR_CHECK='TRUE';
      ALLOW_CONNECT='TRUE';
    'G2':
      PIN_NUMBER='(G2)';
      PINUSE='GROUND';
      NO_LOAD_CHECK='Both';
      NO_IO_CHECK='Both';
      NO_ASSERT_CHECK='TRUE';
      NO_DIR_CHECK='TRUE';
      ALLOW_CONNECT='TRUE';
    'GH1':
      PIN_NUMBER='(GH1)';
      OUTPUT_TYPE='(TS,TS)';
      BIDIRECTIONAL='TRUE';
      INPUT_LOAD='(-0.01,0.01)';
      OUTPUT_LOAD='(1.0,-1.0)';
      PINUSE='BI';
    'GH2':
      PIN_NUMBER='(GH2)';
      OUTPUT_TYPE='(TS,TS)';
      BIDIRECTIONAL='TRUE';
      INPUT_LOAD='(-0.01,0.01)';
      OUTPUT_LOAD='(1.0,-1.0)';
      PINUSE='BI';
    'GH3':
      PIN_NUMBER='(GH3)';
      OUTPUT_TYPE='(TS,TS)';
      BIDIRECTIONAL='TRUE';
      INPUT_LOAD='(-0.01,0.01)';
      OUTPUT_LOAD='(1.0,-1.0)';
      PINUSE='BI';
    'GH4':
      PIN_NUMBER='(GH4)';
      OUTPUT_TYPE='(TS,TS)';
      BIDIRECTIONAL='TRUE';
      INPUT_LOAD='(-0.01,0.01)';
      OUTPUT_LOAD='(1.0,-1.0)';
      PINUSE='BI';
  end_pin;
  body
      PART_NAME='CONN_USB_1X5_G2_GH4_F_RA_SMT';
      BODY_NAME='CONN_USB_1X5_G2_GH4_F_RA_SMT';
      PHYS_DES_PREFIX='J';
      CLASS='IO';
      JEDEC_TYPE='S_F_USB_1X5_G2_GH4_RA_P0256';
      ALT_SYMBOLS='(S_F_USB_1X5_G2_GH4_RA_P0256)';
      DESCRIPTION='CON,MICRO USB BOTTOM MOUNT RECEPTACLE,B TYPE,RA,SMT';
      PARENT_PART_TYPE='CONN_USB_1X5_G2_GH4_F_RA_SMT';
      PARENT_PPT='CONN_USB_1X5_G2_GH4_F_RA_SMT';
      PARENT_PPT_PART='CONN_USB_1X5_G2_GH4_F_RA_SMT-G200-12192-01,1050171001';
  end_body;
end_primitive;
primitive 'DIODE_2-G122-00005-01';
  pin
    'C':
      PIN_NUMBER='(C)';
      OUTPUT_TYPE='(TS,TS)';
      BIDIRECTIONAL='TRUE';
      INPUT_LOAD='(-0.01,0.01)';
      OUTPUT_LOAD='(1.0,-1.0)';
      PINUSE='BI';
    'A':
      PIN_NUMBER='(A)';
      OUTPUT_TYPE='(TS,TS)';
      BIDIRECTIONAL='TRUE';
      INPUT_LOAD='(-0.01,0.01)';
      OUTPUT_LOAD='(1.0,-1.0)';
      PINUSE='BI';
  end_pin;
  body
      PART_NAME='DIODE_2';
      BODY_NAME='DIODE_2';
      PHYS_DES_PREFIX='CR';
      CLASS='DISCRETE';
      JEDEC_TYPE='SMC_CR_170X143_V2';
      ALT_SYMBOLS='(SMC_CR_170X143_V2)';
      DESCRIPTION='DIO,MBRS240,SCHOTTKY_PWR_RECT,2A,40V,SMB';
      CPN_STATUS='';
      PARENT_PART_TYPE='DIODE_2';
      PARENT_PPT='DIODE_2';
      PARENT_PPT_PART='DIODE_2-G122-00005-01';
  end_body;
end_primitive;
primitive 'DIODE_2E-G122-10190-01';
  pin
    'C':
      PIN_NUMBER='(C)';
      OUTPUT_TYPE='(TS,TS)';
      BIDIRECTIONAL='TRUE';
      INPUT_LOAD='(-0.01,0.01)';
      OUTPUT_LOAD='(1.0,-1.0)';
      PINUSE='BI';
    'A':
      PIN_NUMBER='(A)';
      OUTPUT_TYPE='(TS,TS)';
      BIDIRECTIONAL='TRUE';
      INPUT_LOAD='(-0.01,0.01)';
      OUTPUT_LOAD='(1.0,-1.0)';
      PINUSE='BI';
  end_pin;
  body
      PART_NAME='DIODE_2E';
      BODY_NAME='DIODE_2E';
      PHYS_DES_PREFIX='CR';
      CLASS='DISCRETE';
      JEDEC_TYPE='SMC_CR_270X232_V1';
      ALT_SYMBOLS='(SMC_CR_270X232_V1)';
      DESCRIPTION='DIO,TVS,SMDJ,12V,0.001A,DO214B';
      CPN_STATUS='';
      PARENT_PART_TYPE='DIODE_2E';
      PARENT_PPT='DIODE_2E';
      PARENT_PPT_PART='DIODE_2E-G122-10190-01';
  end_body;
end_primitive;
primitive 'DIODE_2F-G122-10186-01';
  pin
    'C':
      PIN_NUMBER='(C)';
      OUTPUT_TYPE='(TS,TS)';
      BIDIRECTIONAL='TRUE';
      INPUT_LOAD='(-0.01,0.01)';
      OUTPUT_LOAD='(1.0,-1.0)';
      PINUSE='BI';
    'A':
      PIN_NUMBER='(A)';
      OUTPUT_TYPE='(TS,TS)';
      BIDIRECTIONAL='TRUE';
      INPUT_LOAD='(-0.01,0.01)';
      OUTPUT_LOAD='(1.0,-1.0)';
      PINUSE='BI';
  end_pin;
  body
      PART_NAME='DIODE_2F';
      BODY_NAME='DIODE_2F';
      PHYS_DES_PREFIX='CR';
      CLASS='DISCRETE';
      JEDEC_TYPE='SMC_CR_067X049_V1';
      ALT_SYMBOLS='(SMC_CR_067X049_V1)';
      DESCRIPTION='DIO,SCHOTTKY,20V,1A,SOD323';
      CPN_STATUS='';
      PARENT_PART_TYPE='DIODE_2F';
      PARENT_PPT='DIODE_2F';
      PARENT_PPT_PART='DIODE_2F-G122-10186-01';
  end_body;
end_primitive;
primitive 'DIODE_3F-G122-10080-01';
  pin
    'A_1':
      PIN_NUMBER='(1)';
      OUTPUT_TYPE='(TS,TS)';
      BIDIRECTIONAL='TRUE';
      INPUT_LOAD='(-0.01,0.01)';
      OUTPUT_LOAD='(1.0,-1.0)';
      PINUSE='BI';
    'A_2':
      PIN_NUMBER='(2)';
      OUTPUT_TYPE='(TS,TS)';
      BIDIRECTIONAL='TRUE';
      INPUT_LOAD='(-0.01,0.01)';
      OUTPUT_LOAD='(1.0,-1.0)';
      PINUSE='BI';
    'C':
      PIN_NUMBER='(3)';
      OUTPUT_TYPE='(TS,TS)';
      BIDIRECTIONAL='TRUE';
      INPUT_LOAD='(-0.01,0.01)';
      OUTPUT_LOAD='(1.0,-1.0)';
      PINUSE='BI';
  end_pin;
  body
      PART_NAME='DIODE_3F';
      BODY_NAME='DIODE_3F';
      PHYS_DES_PREFIX='CR';
      CLASS='DISCRETE';
      JEDEC_TYPE='DPAK_3_V3';
      ALT_SYMBOLS='(DPAK_3_V3)';
      DESCRIPTION='DIO,SCHOTTKY,V20W60C-M3,60V,20A,TO-252';
      CPN_STATUS='';
      PARENT_PART_TYPE='DIODE_3F';
      PARENT_PPT='DIODE_3F';
      PARENT_PPT_PART='DIODE_3F-G122-10080-01';
  end_body;
end_primitive;
primitive 'DIODE_4_V1-G122-10123-01';
  pin
    'GND':
      PIN_NUMBER='(1)';
      PINUSE='GROUND';
      NO_LOAD_CHECK='Both';
      NO_IO_CHECK='Both';
      NO_ASSERT_CHECK='TRUE';
      NO_DIR_CHECK='TRUE';
      ALLOW_CONNECT='TRUE';
    'IO1':
      PIN_NUMBER='(2)';
      OUTPUT_TYPE='(TS,TS)';
      BIDIRECTIONAL='TRUE';
      INPUT_LOAD='(-0.01,0.01)';
      OUTPUT_LOAD='(1.0,-1.0)';
      PINUSE='BI';
    'IO2':
      PIN_NUMBER='(3)';
      OUTPUT_TYPE='(TS,TS)';
      BIDIRECTIONAL='TRUE';
      INPUT_LOAD='(-0.01,0.01)';
      OUTPUT_LOAD='(1.0,-1.0)';
      PINUSE='BI';
    'VDD':
      PIN_NUMBER='(4)';
      PINUSE='POWER';
      NO_LOAD_CHECK='Both';
      NO_IO_CHECK='Both';
      NO_ASSERT_CHECK='TRUE';
      NO_DIR_CHECK='TRUE';
      ALLOW_CONNECT='TRUE';
  end_pin;
  body
      PART_NAME='DIODE_4_V1';
      BODY_NAME='DIODE_4_V1';
      PHYS_DES_PREFIX='CR';
      CLASS='DISCRETE';
      JEDEC_TYPE='SOT143';
      ALT_SYMBOLS='(SOT143)';
      DESCRIPTION='DIO,TVS,3.3VRWM,12A,SOT143-4L,SMT';
      PARENT_PART_TYPE='DIODE_4_V1';
      PARENT_PPT='DIODE_4_V1';
      PARENT_PPT_PART='DIODE_4_V1-G122-10123-01';
  end_body;
end_primitive;
primitive 'FERRITEBEAD-G191-10097-01,600OA';
  pin
    '1':
      PIN_NUMBER='(1)';
      PINUSE='UNSPEC';
    '2':
      PIN_NUMBER='(2)';
      PINUSE='UNSPEC';
  end_pin;
  body
      PART_NAME='FERRITEBEAD';
      BODY_NAME='FERRITEBEAD';
      PHYS_DES_PREFIX='L';
      CLASS='DISCRETE';
      JEDEC_TYPE='SMC_0603R_H037';
      ALT_SYMBOLS='(SMC_0603R_H037)';
      DESCRIPTION='FER,600OHM@100MHZ,1.3A,150MOHM,0603';
      CPN_STATUS='PREFER';
      PARENT_PART_TYPE='FERRITEBEAD';
      PARENT_PPT='FERRITEBEAD';
      PARENT_PPT_PART='FERRITEBEAD-G191-10097-01,600OHM,25%';
  end_body;
end_primitive;
primitive 'FERRITEBEAD-G191-10100-01,120OA';
  pin
    '1':
      PIN_NUMBER='(1)';
      PINUSE='UNSPEC';
    '2':
      PIN_NUMBER='(2)';
      PINUSE='UNSPEC';
  end_pin;
  body
      PART_NAME='FERRITEBEAD';
      BODY_NAME='FERRITEBEAD';
      PHYS_DES_PREFIX='L';
      CLASS='DISCRETE';
      JEDEC_TYPE='SMC_0603R_H030';
      ALT_SYMBOLS='(SMC_0603R_H030)';
      DESCRIPTION='FER,120OHM@100MHZ,3A,30MOHM,0603';
      CPN_STATUS='PREFER';
      PARENT_PART_TYPE='FERRITEBEAD';
      PARENT_PPT='FERRITEBEAD';
      PARENT_PPT_PART='FERRITEBEAD-G191-10100-01,120OHM,25%';
  end_body;
end_primitive;
primitive 'FERRITEBEAD-G191-10101-01,26OHA';
  pin
    '1':
      PIN_NUMBER='(1)';
      PINUSE='UNSPEC';
    '2':
      PIN_NUMBER='(2)';
      PINUSE='UNSPEC';
  end_pin;
  body
      PART_NAME='FERRITEBEAD';
      BODY_NAME='FERRITEBEAD';
      PHYS_DES_PREFIX='L';
      CLASS='DISCRETE';
      JEDEC_TYPE='SMC_0603R_H030';
      ALT_SYMBOLS='(SMC_0603R_H030)';
      DESCRIPTION='FER,26OHM@100MHZ,6A,7MOHM,0603';
      CPN_STATUS='PREFER';
      PARENT_PART_TYPE='FERRITEBEAD';
      PARENT_PPT='FERRITEBEAD';
      PARENT_PPT_PART='FERRITEBEAD-G191-10101-01,26OHM,25%';
  end_body;
end_primitive;
primitive 'FT4232HL_REEL_QFP64-G223-10282A';
  pin
    'ADBUS0':
      PIN_NUMBER='(16)';
      OUTPUT_TYPE='(TS,TS)';
      BIDIRECTIONAL='TRUE';
      INPUT_LOAD='(-0.01,0.01)';
      OUTPUT_LOAD='(1.0,-1.0)';
      PINUSE='BI';
    'ADBUS1':
      PIN_NUMBER='(17)';
      OUTPUT_TYPE='(TS,TS)';
      BIDIRECTIONAL='TRUE';
      INPUT_LOAD='(-0.01,0.01)';
      OUTPUT_LOAD='(1.0,-1.0)';
      PINUSE='BI';
    'ADBUS2':
      PIN_NUMBER='(18)';
      OUTPUT_TYPE='(TS,TS)';
      BIDIRECTIONAL='TRUE';
      INPUT_LOAD='(-0.01,0.01)';
      OUTPUT_LOAD='(1.0,-1.0)';
      PINUSE='BI';
    'ADBUS3':
      PIN_NUMBER='(19)';
      OUTPUT_TYPE='(TS,TS)';
      BIDIRECTIONAL='TRUE';
      INPUT_LOAD='(-0.01,0.01)';
      OUTPUT_LOAD='(1.0,-1.0)';
      PINUSE='BI';
    'ADBUS4':
      PIN_NUMBER='(21)';
      OUTPUT_TYPE='(TS,TS)';
      BIDIRECTIONAL='TRUE';
      INPUT_LOAD='(-0.01,0.01)';
      OUTPUT_LOAD='(1.0,-1.0)';
      PINUSE='BI';
    'ADBUS5':
      PIN_NUMBER='(22)';
      OUTPUT_TYPE='(TS,TS)';
      BIDIRECTIONAL='TRUE';
      INPUT_LOAD='(-0.01,0.01)';
      OUTPUT_LOAD='(1.0,-1.0)';
      PINUSE='BI';
    'ADBUS6':
      PIN_NUMBER='(23)';
      OUTPUT_TYPE='(TS,TS)';
      BIDIRECTIONAL='TRUE';
      INPUT_LOAD='(-0.01,0.01)';
      OUTPUT_LOAD='(1.0,-1.0)';
      PINUSE='BI';
    'ADBUS7':
      PIN_NUMBER='(24)';
      OUTPUT_TYPE='(TS,TS)';
      BIDIRECTIONAL='TRUE';
      INPUT_LOAD='(-0.01,0.01)';
      OUTPUT_LOAD='(1.0,-1.0)';
      PINUSE='BI';
    'BDBUS0':
      PIN_NUMBER='(26)';
      OUTPUT_TYPE='(TS,TS)';
      BIDIRECTIONAL='TRUE';
      INPUT_LOAD='(-0.01,0.01)';
      OUTPUT_LOAD='(1.0,-1.0)';
      PINUSE='BI';
    'BDBUS1':
      PIN_NUMBER='(27)';
      OUTPUT_TYPE='(TS,TS)';
      BIDIRECTIONAL='TRUE';
      INPUT_LOAD='(-0.01,0.01)';
      OUTPUT_LOAD='(1.0,-1.0)';
      PINUSE='BI';
    'BDBUS2':
      PIN_NUMBER='(28)';
      OUTPUT_TYPE='(TS,TS)';
      BIDIRECTIONAL='TRUE';
      INPUT_LOAD='(-0.01,0.01)';
      OUTPUT_LOAD='(1.0,-1.0)';
      PINUSE='BI';
    'BDBUS3':
      PIN_NUMBER='(29)';
      OUTPUT_TYPE='(TS,TS)';
      BIDIRECTIONAL='TRUE';
      INPUT_LOAD='(-0.01,0.01)';
      OUTPUT_LOAD='(1.0,-1.0)';
      PINUSE='BI';
    'BDBUS4':
      PIN_NUMBER='(30)';
      OUTPUT_TYPE='(TS,TS)';
      BIDIRECTIONAL='TRUE';
      INPUT_LOAD='(-0.01,0.01)';
      OUTPUT_LOAD='(1.0,-1.0)';
      PINUSE='BI';
    'BDBUS5':
      PIN_NUMBER='(32)';
      OUTPUT_TYPE='(TS,TS)';
      BIDIRECTIONAL='TRUE';
      INPUT_LOAD='(-0.01,0.01)';
      OUTPUT_LOAD='(1.0,-1.0)';
      PINUSE='BI';
    'BDBUS6':
      PIN_NUMBER='(33)';
      OUTPUT_TYPE='(TS,TS)';
      BIDIRECTIONAL='TRUE';
      INPUT_LOAD='(-0.01,0.01)';
      OUTPUT_LOAD='(1.0,-1.0)';
      PINUSE='BI';
    'BDBUS7':
      PIN_NUMBER='(34)';
      OUTPUT_TYPE='(TS,TS)';
      BIDIRECTIONAL='TRUE';
      INPUT_LOAD='(-0.01,0.01)';
      OUTPUT_LOAD='(1.0,-1.0)';
      PINUSE='BI';
    'CDBUS0':
      PIN_NUMBER='(38)';
      OUTPUT_TYPE='(TS,TS)';
      BIDIRECTIONAL='TRUE';
      INPUT_LOAD='(-0.01,0.01)';
      OUTPUT_LOAD='(1.0,-1.0)';
      PINUSE='BI';
    'CDBUS1':
      PIN_NUMBER='(39)';
      OUTPUT_TYPE='(TS,TS)';
      BIDIRECTIONAL='TRUE';
      INPUT_LOAD='(-0.01,0.01)';
      OUTPUT_LOAD='(1.0,-1.0)';
      PINUSE='BI';
    'CDBUS2':
      PIN_NUMBER='(40)';
      OUTPUT_TYPE='(TS,TS)';
      BIDIRECTIONAL='TRUE';
      INPUT_LOAD='(-0.01,0.01)';
      OUTPUT_LOAD='(1.0,-1.0)';
      PINUSE='BI';
    'CDBUS3':
      PIN_NUMBER='(41)';
      OUTPUT_TYPE='(TS,TS)';
      BIDIRECTIONAL='TRUE';
      INPUT_LOAD='(-0.01,0.01)';
      OUTPUT_LOAD='(1.0,-1.0)';
      PINUSE='BI';
    'CDBUS4':
      PIN_NUMBER='(43)';
      OUTPUT_TYPE='(TS,TS)';
      BIDIRECTIONAL='TRUE';
      INPUT_LOAD='(-0.01,0.01)';
      OUTPUT_LOAD='(1.0,-1.0)';
      PINUSE='BI';
    'CDBUS5':
      PIN_NUMBER='(44)';
      OUTPUT_TYPE='(TS,TS)';
      BIDIRECTIONAL='TRUE';
      INPUT_LOAD='(-0.01,0.01)';
      OUTPUT_LOAD='(1.0,-1.0)';
      PINUSE='BI';
    'CDBUS6':
      PIN_NUMBER='(45)';
      OUTPUT_TYPE='(TS,TS)';
      BIDIRECTIONAL='TRUE';
      INPUT_LOAD='(-0.01,0.01)';
      OUTPUT_LOAD='(1.0,-1.0)';
      PINUSE='BI';
    'CDBUS7':
      PIN_NUMBER='(46)';
      OUTPUT_TYPE='(TS,TS)';
      BIDIRECTIONAL='TRUE';
      INPUT_LOAD='(-0.01,0.01)';
      OUTPUT_LOAD='(1.0,-1.0)';
      PINUSE='BI';
    'DDBUS0':
      PIN_NUMBER='(48)';
      OUTPUT_TYPE='(TS,TS)';
      BIDIRECTIONAL='TRUE';
      INPUT_LOAD='(-0.01,0.01)';
      OUTPUT_LOAD='(1.0,-1.0)';
      PINUSE='BI';
    'DDBUS1':
      PIN_NUMBER='(52)';
      OUTPUT_TYPE='(TS,TS)';
      BIDIRECTIONAL='TRUE';
      INPUT_LOAD='(-0.01,0.01)';
      OUTPUT_LOAD='(1.0,-1.0)';
      PINUSE='BI';
    'DDBUS2':
      PIN_NUMBER='(53)';
      OUTPUT_TYPE='(TS,TS)';
      BIDIRECTIONAL='TRUE';
      INPUT_LOAD='(-0.01,0.01)';
      OUTPUT_LOAD='(1.0,-1.0)';
      PINUSE='BI';
    'DDBUS3':
      PIN_NUMBER='(54)';
      OUTPUT_TYPE='(TS,TS)';
      BIDIRECTIONAL='TRUE';
      INPUT_LOAD='(-0.01,0.01)';
      OUTPUT_LOAD='(1.0,-1.0)';
      PINUSE='BI';
    'DDBUS4':
      PIN_NUMBER='(55)';
      OUTPUT_TYPE='(TS,TS)';
      BIDIRECTIONAL='TRUE';
      INPUT_LOAD='(-0.01,0.01)';
      OUTPUT_LOAD='(1.0,-1.0)';
      PINUSE='BI';
    'DDBUS5':
      PIN_NUMBER='(57)';
      OUTPUT_TYPE='(TS,TS)';
      BIDIRECTIONAL='TRUE';
      INPUT_LOAD='(-0.01,0.01)';
      OUTPUT_LOAD='(1.0,-1.0)';
      PINUSE='BI';
    'DDBUS6':
      PIN_NUMBER='(58)';
      OUTPUT_TYPE='(TS,TS)';
      BIDIRECTIONAL='TRUE';
      INPUT_LOAD='(-0.01,0.01)';
      OUTPUT_LOAD='(1.0,-1.0)';
      PINUSE='BI';
    'DDBUS7':
      PIN_NUMBER='(59)';
      OUTPUT_TYPE='(TS,TS)';
      BIDIRECTIONAL='TRUE';
      INPUT_LOAD='(-0.01,0.01)';
      OUTPUT_LOAD='(1.0,-1.0)';
      PINUSE='BI';
    'PWREN*':
      PIN_NUMBER='(60)';
      OUTPUT_TYPE='(TS,TS)';
      BIDIRECTIONAL='TRUE';
      INPUT_LOAD='(-0.01,0.01)';
      OUTPUT_LOAD='(1.0,-1.0)';
      PINUSE='BI';
    'SUSPEND*':
      PIN_NUMBER='(36)';
      OUTPUT_TYPE='(TS,TS)';
      BIDIRECTIONAL='TRUE';
      INPUT_LOAD='(-0.01,0.01)';
      OUTPUT_LOAD='(1.0,-1.0)';
      PINUSE='BI';
    'VREGIN':
      PIN_NUMBER='(50)';
      INPUT_LOAD='(-0.01,0.01)';
      PINUSE='IN';
    'VREGOUT':
      PIN_NUMBER='(49)';
      OUTPUT_LOAD='(1.0,-1.0)';
      PINUSE='OUT';
    'VCCIO_1':
      PIN_NUMBER='(56)';
      PINUSE='POWER';
      NO_LOAD_CHECK='Both';
      NO_IO_CHECK='Both';
      NO_ASSERT_CHECK='TRUE';
      NO_DIR_CHECK='TRUE';
      ALLOW_CONNECT='TRUE';
    'VCCIO_2':
      PIN_NUMBER='(42)';
      PINUSE='POWER';
      NO_LOAD_CHECK='Both';
      NO_IO_CHECK='Both';
      NO_ASSERT_CHECK='TRUE';
      NO_DIR_CHECK='TRUE';
      ALLOW_CONNECT='TRUE';
    'VCCIO_3':
      PIN_NUMBER='(31)';
      PINUSE='POWER';
      NO_LOAD_CHECK='Both';
      NO_IO_CHECK='Both';
      NO_ASSERT_CHECK='TRUE';
      NO_DIR_CHECK='TRUE';
      ALLOW_CONNECT='TRUE';
    'VCCIO_4':
      PIN_NUMBER='(20)';
      PINUSE='POWER';
      NO_LOAD_CHECK='Both';
      NO_IO_CHECK='Both';
      NO_ASSERT_CHECK='TRUE';
      NO_DIR_CHECK='TRUE';
      ALLOW_CONNECT='TRUE';
    'VCORE_1':
      PIN_NUMBER='(64)';
      PINUSE='POWER';
      NO_LOAD_CHECK='Both';
      NO_IO_CHECK='Both';
      NO_ASSERT_CHECK='TRUE';
      NO_DIR_CHECK='TRUE';
      ALLOW_CONNECT='TRUE';
    'VCORE_2':
      PIN_NUMBER='(37)';
      PINUSE='POWER';
      NO_LOAD_CHECK='Both';
      NO_IO_CHECK='Both';
      NO_ASSERT_CHECK='TRUE';
      NO_DIR_CHECK='TRUE';
      ALLOW_CONNECT='TRUE';
    'VCORE_3':
      PIN_NUMBER='(12)';
      PINUSE='POWER';
      NO_LOAD_CHECK='Both';
      NO_IO_CHECK='Both';
      NO_ASSERT_CHECK='TRUE';
      NO_DIR_CHECK='TRUE';
      ALLOW_CONNECT='TRUE';
    'VPLL':
      PIN_NUMBER='(9)';
      OUTPUT_TYPE='(TS,TS)';
      BIDIRECTIONAL='TRUE';
      INPUT_LOAD='(-0.01,0.01)';
      OUTPUT_LOAD='(1.0,-1.0)';
      PINUSE='BI';
    'VPHY':
      PIN_NUMBER='(4)';
      OUTPUT_TYPE='(TS,TS)';
      BIDIRECTIONAL='TRUE';
      INPUT_LOAD='(-0.01,0.01)';
      OUTPUT_LOAD='(1.0,-1.0)';
      PINUSE='BI';
    'AGND':
      PIN_NUMBER='(10)';
      PINUSE='GROUND';
      NO_LOAD_CHECK='Both';
      NO_IO_CHECK='Both';
      NO_ASSERT_CHECK='TRUE';
      NO_DIR_CHECK='TRUE';
      ALLOW_CONNECT='TRUE';
    'GND_1':
      PIN_NUMBER='(51)';
      PINUSE='GROUND';
      NO_LOAD_CHECK='Both';
      NO_IO_CHECK='Both';
      NO_ASSERT_CHECK='TRUE';
      NO_DIR_CHECK='TRUE';
      ALLOW_CONNECT='TRUE';
    'GND_2':
      PIN_NUMBER='(47)';
      PINUSE='GROUND';
      NO_LOAD_CHECK='Both';
      NO_IO_CHECK='Both';
      NO_ASSERT_CHECK='TRUE';
      NO_DIR_CHECK='TRUE';
      ALLOW_CONNECT='TRUE';
    'GND_3':
      PIN_NUMBER='(35)';
      PINUSE='GROUND';
      NO_LOAD_CHECK='Both';
      NO_IO_CHECK='Both';
      NO_ASSERT_CHECK='TRUE';
      NO_DIR_CHECK='TRUE';
      ALLOW_CONNECT='TRUE';
    'GND_4':
      PIN_NUMBER='(25)';
      PINUSE='GROUND';
      NO_LOAD_CHECK='Both';
      NO_IO_CHECK='Both';
      NO_ASSERT_CHECK='TRUE';
      NO_DIR_CHECK='TRUE';
      ALLOW_CONNECT='TRUE';
    'GND_5':
      PIN_NUMBER='(15)';
      PINUSE='GROUND';
      NO_LOAD_CHECK='Both';
      NO_IO_CHECK='Both';
      NO_ASSERT_CHECK='TRUE';
      NO_DIR_CHECK='TRUE';
      ALLOW_CONNECT='TRUE';
    'GND_6':
      PIN_NUMBER='(11)';
      PINUSE='GROUND';
      NO_LOAD_CHECK='Both';
      NO_IO_CHECK='Both';
      NO_ASSERT_CHECK='TRUE';
      NO_DIR_CHECK='TRUE';
      ALLOW_CONNECT='TRUE';
    'GND_7':
      PIN_NUMBER='(5)';
      PINUSE='GROUND';
      NO_LOAD_CHECK='Both';
      NO_IO_CHECK='Both';
      NO_ASSERT_CHECK='TRUE';
      NO_DIR_CHECK='TRUE';
      ALLOW_CONNECT='TRUE';
    'GND_8':
      PIN_NUMBER='(1)';
      PINUSE='GROUND';
      NO_LOAD_CHECK='Both';
      NO_IO_CHECK='Both';
      NO_ASSERT_CHECK='TRUE';
      NO_DIR_CHECK='TRUE';
      ALLOW_CONNECT='TRUE';
    'DM':
      PIN_NUMBER='(7)';
      OUTPUT_TYPE='(TS,TS)';
      BIDIRECTIONAL='TRUE';
      INPUT_LOAD='(-0.01,0.01)';
      OUTPUT_LOAD='(1.0,-1.0)';
      PINUSE='BI';
    'DP':
      PIN_NUMBER='(8)';
      OUTPUT_TYPE='(TS,TS)';
      BIDIRECTIONAL='TRUE';
      INPUT_LOAD='(-0.01,0.01)';
      OUTPUT_LOAD='(1.0,-1.0)';
      PINUSE='BI';
    'REF':
      PIN_NUMBER='(6)';
      INPUT_LOAD='(-0.01,0.01)';
      PINUSE='IN';
    'RESET*':
      PIN_NUMBER='(14)';
      OUTPUT_TYPE='(TS,TS)';
      BIDIRECTIONAL='TRUE';
      INPUT_LOAD='(-0.01,0.01)';
      OUTPUT_LOAD='(1.0,-1.0)';
      PINUSE='BI';
    'EECS':
      PIN_NUMBER='(63)';
      OUTPUT_TYPE='(TS,TS)';
      BIDIRECTIONAL='TRUE';
      INPUT_LOAD='(-0.01,0.01)';
      OUTPUT_LOAD='(1.0,-1.0)';
      PINUSE='BI';
    'EECLK':
      PIN_NUMBER='(62)';
      OUTPUT_TYPE='(TS,TS)';
      BIDIRECTIONAL='TRUE';
      INPUT_LOAD='(-0.01,0.01)';
      OUTPUT_LOAD='(1.0,-1.0)';
      PINUSE='BI';
    'EEDATA':
      PIN_NUMBER='(61)';
      OUTPUT_TYPE='(TS,TS)';
      BIDIRECTIONAL='TRUE';
      INPUT_LOAD='(-0.01,0.01)';
      OUTPUT_LOAD='(1.0,-1.0)';
      PINUSE='BI';
    'OSCI':
      PIN_NUMBER='(2)';
      OUTPUT_TYPE='(TS,TS)';
      BIDIRECTIONAL='TRUE';
      INPUT_LOAD='(-0.01,0.01)';
      OUTPUT_LOAD='(1.0,-1.0)';
      PINUSE='BI';
    'OSCO':
      PIN_NUMBER='(3)';
      OUTPUT_TYPE='(TS,TS)';
      BIDIRECTIONAL='TRUE';
      INPUT_LOAD='(-0.01,0.01)';
      OUTPUT_LOAD='(1.0,-1.0)';
      PINUSE='BI';
    'TEST':
      PIN_NUMBER='(13)';
      OUTPUT_TYPE='(TS,TS)';
      BIDIRECTIONAL='TRUE';
      INPUT_LOAD='(-0.01,0.01)';
      OUTPUT_LOAD='(1.0,-1.0)';
      PINUSE='BI';
  end_pin;
  body
      PART_NAME='FT4232HL_REEL_QFP64';
      BODY_NAME='FT4232HL_REEL_QFP64';
      PHYS_DES_PREFIX='U';
      CLASS='IC';
      JEDEC_TYPE='QFP64_394_P0197_V1';
      ALT_SYMBOLS='(QFP64_394_P0197_V1)';
      DESCRIPTION='IC,FT4232H,USB TO UART,LQFP-64';
      CPN_STATUS='';
      PARENT_PART_TYPE='FT4232HL_REEL_QFP64';
      PARENT_PPT='FT4232HL_REEL_QFP64';
      PARENT_PPT_PART='FT4232HL_REEL_QFP64-G223-10282-01,FT4232HL-REEL';
  end_body;
end_primitive;
primitive 'FUSE-G280-10012-01,2.5A';
  pin
    '1':
      PIN_NUMBER='(1)';
      OUTPUT_TYPE='(TS,TS)';
      BIDIRECTIONAL='TRUE';
      INPUT_LOAD='(-0.01,0.01)';
      OUTPUT_LOAD='(1.0,-1.0)';
      PINUSE='BI';
    '2':
      PIN_NUMBER='(2)';
      OUTPUT_TYPE='(TS,TS)';
      BIDIRECTIONAL='TRUE';
      INPUT_LOAD='(-0.01,0.01)';
      OUTPUT_LOAD='(1.0,-1.0)';
      PINUSE='BI';
  end_pin;
  body
      PART_NAME='FUSE';
      BODY_NAME='FUSE';
      PHYS_DES_PREFIX='FU';
      CLASS='DISCRETE';
      JEDEC_TYPE='SMC_0603R_H022';
      ALT_SYMBOLS='(SMC_0603R_H022)';
      DESCRIPTION='FUSE,2.5A,32V,0603';
      CPN_STATUS='';
      PARENT_PART_TYPE='FUSE';
      PARENT_PPT='FUSE';
      PARENT_PPT_PART='FUSE-G280-10012-01,2.5A';
  end_body;
end_primitive;
primitive 'FUSE-G280-10049-01,1A';
  pin
    '1':
      PIN_NUMBER='(1)';
      OUTPUT_TYPE='(TS,TS)';
      BIDIRECTIONAL='TRUE';
      INPUT_LOAD='(-0.01,0.01)';
      OUTPUT_LOAD='(1.0,-1.0)';
      PINUSE='BI';
    '2':
      PIN_NUMBER='(2)';
      OUTPUT_TYPE='(TS,TS)';
      BIDIRECTIONAL='TRUE';
      INPUT_LOAD='(-0.01,0.01)';
      OUTPUT_LOAD='(1.0,-1.0)';
      PINUSE='BI';
  end_pin;
  body
      PART_NAME='FUSE';
      BODY_NAME='FUSE';
      PHYS_DES_PREFIX='FU';
      CLASS='DISCRETE';
      JEDEC_TYPE='SMC_0603R_H024';
      ALT_SYMBOLS='(SMC_0603R_H024)';
      DESCRIPTION='FUSE,1A,63V,0.310OHM,0.0593A2SEC,0603';
      CPN_STATUS='';
      PARENT_PART_TYPE='FUSE';
      PARENT_PPT='FUSE';
      PARENT_PPT_PART='FUSE-G280-10049-01,1A';
  end_body;
end_primitive;
primitive 'G200_10283_01-G200-10283-01';
  pin
    '1':
      PIN_NUMBER='(1)';
      OUTPUT_TYPE='(TS,TS)';
      BIDIRECTIONAL='TRUE';
      INPUT_LOAD='(*,*)';
      OUTPUT_LOAD='(*,*)';
      PINUSE='BI';
    '2':
      PIN_NUMBER='(2)';
      OUTPUT_TYPE='(TS,TS)';
      BIDIRECTIONAL='TRUE';
      INPUT_LOAD='(*,*)';
      OUTPUT_LOAD='(*,*)';
      PINUSE='BI';
    '3':
      PIN_NUMBER='(3)';
      OUTPUT_TYPE='(TS,TS)';
      BIDIRECTIONAL='TRUE';
      INPUT_LOAD='(*,*)';
      OUTPUT_LOAD='(*,*)';
      PINUSE='BI';
    '4':
      PIN_NUMBER='(4)';
      OUTPUT_TYPE='(TS,TS)';
      BIDIRECTIONAL='TRUE';
      INPUT_LOAD='(*,*)';
      OUTPUT_LOAD='(*,*)';
      PINUSE='BI';
    '5':
      PIN_NUMBER='(5)';
      OUTPUT_TYPE='(TS,TS)';
      BIDIRECTIONAL='TRUE';
      INPUT_LOAD='(*,*)';
      OUTPUT_LOAD='(*,*)';
      PINUSE='BI';
    '6':
      PIN_NUMBER='(6)';
      OUTPUT_TYPE='(TS,TS)';
      BIDIRECTIONAL='TRUE';
      INPUT_LOAD='(*,*)';
      OUTPUT_LOAD='(*,*)';
      PINUSE='BI';
    '7':
      PIN_NUMBER='(7)';
      OUTPUT_TYPE='(TS,TS)';
      BIDIRECTIONAL='TRUE';
      INPUT_LOAD='(*,*)';
      OUTPUT_LOAD='(*,*)';
      PINUSE='BI';
    '8':
      PIN_NUMBER='(8)';
      OUTPUT_TYPE='(TS,TS)';
      BIDIRECTIONAL='TRUE';
      INPUT_LOAD='(*,*)';
      OUTPUT_LOAD='(*,*)';
      PINUSE='BI';
    '9':
      PIN_NUMBER='(9)';
      OUTPUT_TYPE='(TS,TS)';
      BIDIRECTIONAL='TRUE';
      INPUT_LOAD='(*,*)';
      OUTPUT_LOAD='(*,*)';
      PINUSE='BI';
    '10':
      PIN_NUMBER='(10)';
      OUTPUT_TYPE='(TS,TS)';
      BIDIRECTIONAL='TRUE';
      INPUT_LOAD='(*,*)';
      OUTPUT_LOAD='(*,*)';
      PINUSE='BI';
  end_pin;
  body
      PART_NAME='G200_10283_01';
      BODY_NAME='G200_10283_01';
      PHYS_DES_PREFIX='J';
      CLASS='IO';
      JEDEC_TYPE='S_M_DIL_2X5_P100_V1';
      ALT_SYMBOLS='(S_M_DIL_2X5_P100_V1)';
      DESCRIPTION='CON, 2 X 5 DUAL ROHS, SMT';
      CPN_STATUS='';
      PARENT_PART_TYPE='G200_10283_01';
      PARENT_PPT='G200_10283_01';
      PARENT_PPT_PART='G200_10283_01-G200-10283-01';
  end_body;
end_primitive;
primitive 'G220_10198_01-G223-10197-01';
  pin
    'EN':
      PIN_NUMBER='(1)';
      OUTPUT_TYPE='(TS,TS)';
      BIDIRECTIONAL='TRUE';
      INPUT_LOAD='(-0.01,0.01)';
      OUTPUT_LOAD='(1.0,-1.0)';
      PINUSE='BI';
    'SCLOUT':
      PIN_NUMBER='(2)';
      OUTPUT_LOAD='(1.0,-1.0)';
      PINUSE='OUT';
    'SCLIN':
      PIN_NUMBER='(3)';
      INPUT_LOAD='(-0.01,0.01)';
      PINUSE='IN';
    'GND':
      PIN_NUMBER='(4)';
      PINUSE='GROUND';
      NO_LOAD_CHECK='Both';
      NO_IO_CHECK='Both';
      NO_ASSERT_CHECK='TRUE';
      NO_DIR_CHECK='TRUE';
      ALLOW_CONNECT='TRUE';
    'READY':
      PIN_NUMBER='(5)';
      OUTPUT_TYPE='(TS,TS)';
      BIDIRECTIONAL='TRUE';
      INPUT_LOAD='(-0.01,0.01)';
      OUTPUT_LOAD='(1.0,-1.0)';
      PINUSE='BI';
    'SDAIN':
      PIN_NUMBER='(6)';
      INPUT_LOAD='(-0.01,0.01)';
      PINUSE='IN';
    'SDAOUT':
      PIN_NUMBER='(7)';
      OUTPUT_LOAD='(1.0,-1.0)';
      PINUSE='OUT';
    'VCC':
      PIN_NUMBER='(8)';
      PINUSE='POWER';
      NO_LOAD_CHECK='Both';
      NO_IO_CHECK='Both';
      NO_ASSERT_CHECK='TRUE';
      NO_DIR_CHECK='TRUE';
      ALLOW_CONNECT='TRUE';
  end_pin;
  body
      PART_NAME='G220_10198_01';
      BODY_NAME='G220_10198_01';
      PHYS_DES_PREFIX='U';
      CLASS='IC';
      JEDEC_TYPE='SOP8_154_P050_V1';
      ALT_SYMBOLS='(SOP8_154_P050_V1)';
      DESCRIPTION='IC,PCA9510AD,HOT SWAPPABLE I2C-BUS AND SMBUS BUFFER,SO8';
      CPN_STATUS='NFND';
      PARENT_PART_TYPE='G220_10198_01';
      PARENT_PPT='G220_10198_01';
      PARENT_PPT_PART='G220_10198_01-G223-10197-01';
  end_body;
end_primitive;
primitive 'ICP_10100_LGA10-A222-00002-FB,A';
  pin
    'RESV_1':
      PIN_NUMBER='(1)';
      OUTPUT_TYPE='(TS,TS)';
      BIDIRECTIONAL='TRUE';
      INPUT_LOAD='(-0.01,0.01)';
      OUTPUT_LOAD='(1.0,-1.0)';
      PINUSE='BI';
    'SCL':
      PIN_NUMBER='(2)';
      OUTPUT_TYPE='(TS,TS)';
      BIDIRECTIONAL='TRUE';
      INPUT_LOAD='(-0.01,0.01)';
      OUTPUT_LOAD='(1.0,-1.0)';
      PINUSE='BI';
    'RESV_2':
      PIN_NUMBER='(3)';
      OUTPUT_TYPE='(TS,TS)';
      BIDIRECTIONAL='TRUE';
      INPUT_LOAD='(-0.01,0.01)';
      OUTPUT_LOAD='(1.0,-1.0)';
      PINUSE='BI';
    'SDA':
      PIN_NUMBER='(4)';
      OUTPUT_TYPE='(TS,TS)';
      BIDIRECTIONAL='TRUE';
      INPUT_LOAD='(-0.01,0.01)';
      OUTPUT_LOAD='(1.0,-1.0)';
      PINUSE='BI';
    'RESV_3':
      PIN_NUMBER='(5)';
      OUTPUT_TYPE='(TS,TS)';
      BIDIRECTIONAL='TRUE';
      INPUT_LOAD='(-0.01,0.01)';
      OUTPUT_LOAD='(1.0,-1.0)';
      PINUSE='BI';
    'RESV_4':
      PIN_NUMBER='(6)';
      OUTPUT_TYPE='(TS,TS)';
      BIDIRECTIONAL='TRUE';
      INPUT_LOAD='(-0.01,0.01)';
      OUTPUT_LOAD='(1.0,-1.0)';
      PINUSE='BI';
    'RESV_5':
      PIN_NUMBER='(7)';
      OUTPUT_TYPE='(TS,TS)';
      BIDIRECTIONAL='TRUE';
      INPUT_LOAD='(-0.01,0.01)';
      OUTPUT_LOAD='(1.0,-1.0)';
      PINUSE='BI';
    'GND_1':
      PIN_NUMBER='(8)';
      PINUSE='GROUND';
      NO_LOAD_CHECK='Both';
      NO_IO_CHECK='Both';
      NO_ASSERT_CHECK='TRUE';
      NO_DIR_CHECK='TRUE';
      ALLOW_CONNECT='TRUE';
    'GND_2':
      PIN_NUMBER='(9)';
      PINUSE='GROUND';
      NO_LOAD_CHECK='Both';
      NO_IO_CHECK='Both';
      NO_ASSERT_CHECK='TRUE';
      NO_DIR_CHECK='TRUE';
      ALLOW_CONNECT='TRUE';
    'VDD':
      PIN_NUMBER='(10)';
      PINUSE='POWER';
      NO_LOAD_CHECK='Both';
      NO_IO_CHECK='Both';
      NO_ASSERT_CHECK='TRUE';
      NO_DIR_CHECK='TRUE';
      ALLOW_CONNECT='TRUE';
  end_pin;
  body
      PART_NAME='ICP_10100_LGA10';
      BODY_NAME='ICP_10100_LGA10';
      PHYS_DES_PREFIX='U';
      CLASS='IC';
      JEDEC_TYPE='LGA10_079_P0197';
      ALT_SYMBOLS='(LGA10_079_P0197)';
      DESCRIPTION='IC,ICP-10100,BAROMETRIC PRESSURE AND TEMPERATURE SENSOR,SMT,L~
GA-10L';
      CPN_STATUS='';
      PARENT_PART_TYPE='ICP_10100_LGA10';
      PARENT_PPT='ICP_10100_LGA10';
      PARENT_PPT_PART='ICP_10100_LGA10-A222-00002-FB,ICP-10100';
  end_body;
end_primitive;
primitive 'INDUCTOR_2-G190-10418-01,1.0UHA';
  pin
    '1':
      PIN_NUMBER='(1)';
      OUTPUT_TYPE='(TS,TS)';
      BIDIRECTIONAL='TRUE';
      INPUT_LOAD='(-0.01,0.01)';
      OUTPUT_LOAD='(1.0,-1.0)';
      PINUSE='BI';
    '2':
      PIN_NUMBER='(2)';
      OUTPUT_TYPE='(TS,TS)';
      BIDIRECTIONAL='TRUE';
      INPUT_LOAD='(-0.01,0.01)';
      OUTPUT_LOAD='(1.0,-1.0)';
      PINUSE='BI';
  end_pin;
  body
      PART_NAME='INDUCTOR_2';
      BODY_NAME='INDUCTOR_2';
      PHYS_DES_PREFIX='L';
      CLASS='DISCRETE';
      JEDEC_TYPE='SMC_L_287X260_V1_H197';
      ALT_SYMBOLS='(SMC_L_287X260_V1_H197)';
      DESCRIPTION='IND,1.0UH,6.5MOHM,15/20A,7.6X6.9X5MM,SMT';
      CPN_STATUS='PREFER';
      PARENT_PART_TYPE='INDUCTOR_2';
      PARENT_PPT='INDUCTOR_2';
      PARENT_PPT_PART='INDUCTOR_2-G190-10418-01,1.0UH,20%';
  end_body;
end_primitive;
primitive 'INDUCTOR_2-G190-10424-01,4.7UHA';
  pin
    '1':
      PIN_NUMBER='(1)';
      OUTPUT_TYPE='(TS,TS)';
      BIDIRECTIONAL='TRUE';
      INPUT_LOAD='(-0.01,0.01)';
      OUTPUT_LOAD='(1.0,-1.0)';
      PINUSE='BI';
    '2':
      PIN_NUMBER='(2)';
      OUTPUT_TYPE='(TS,TS)';
      BIDIRECTIONAL='TRUE';
      INPUT_LOAD='(-0.01,0.01)';
      OUTPUT_LOAD='(1.0,-1.0)';
      PINUSE='BI';
  end_pin;
  body
      PART_NAME='INDUCTOR_2';
      BODY_NAME='INDUCTOR_2';
      PHYS_DES_PREFIX='L';
      CLASS='DISCRETE';
      JEDEC_TYPE='SMC_L_287X268_V3';
      ALT_SYMBOLS='(SMC_L_287X268_V3)';
      DESCRIPTION='IND,4.7UH,40MOHM,5.5/10A,7.6X7.1X3MM,SMT';
      CPN_STATUS='PREFER';
      PARENT_PART_TYPE='INDUCTOR_2';
      PARENT_PPT='INDUCTOR_2';
      PARENT_PPT_PART='INDUCTOR_2-G190-10424-01,4.7UH,20%';
  end_body;
end_primitive;
primitive 'IS32FL3207_QWLA3_TR_QFN29-A223A';
  pin
    'SDB*':
      PIN_NUMBER='(1)';
      OUTPUT_TYPE='(TS,TS)';
      BIDIRECTIONAL='TRUE';
      INPUT_LOAD='(-0.01,0.01)';
      OUTPUT_LOAD='(1.0,-1.0)';
      PINUSE='BI';
    'AD':
      PIN_NUMBER='(2)';
      OUTPUT_TYPE='(TS,TS)';
      BIDIRECTIONAL='TRUE';
      INPUT_LOAD='(-0.01,0.01)';
      OUTPUT_LOAD='(1.0,-1.0)';
      PINUSE='BI';
    'VCC':
      PIN_NUMBER='(3)';
      PINUSE='POWER';
      NO_LOAD_CHECK='Both';
      NO_IO_CHECK='Both';
      NO_ASSERT_CHECK='TRUE';
      NO_DIR_CHECK='TRUE';
      ALLOW_CONNECT='TRUE';
    'GND_1':
      PIN_NUMBER='(4)';
      PINUSE='GROUND';
      NO_LOAD_CHECK='Both';
      NO_IO_CHECK='Both';
      NO_ASSERT_CHECK='TRUE';
      NO_DIR_CHECK='TRUE';
      ALLOW_CONNECT='TRUE';
    'ISET':
      PIN_NUMBER='(5)';
      OUTPUT_TYPE='(TS,TS)';
      BIDIRECTIONAL='TRUE';
      INPUT_LOAD='(-0.01,0.01)';
      OUTPUT_LOAD='(1.0,-1.0)';
      PINUSE='BI';
    'SDA':
      PIN_NUMBER='(6)';
      OUTPUT_TYPE='(TS,TS)';
      BIDIRECTIONAL='TRUE';
      INPUT_LOAD='(-0.01,0.01)';
      OUTPUT_LOAD='(1.0,-1.0)';
      PINUSE='BI';
    'SCL':
      PIN_NUMBER='(7)';
      OUTPUT_TYPE='(TS,TS)';
      BIDIRECTIONAL='TRUE';
      INPUT_LOAD='(-0.01,0.01)';
      OUTPUT_LOAD='(1.0,-1.0)';
      PINUSE='BI';
    'OUT1':
      PIN_NUMBER='(8)';
      OUTPUT_LOAD='(1.0,-1.0)';
      PINUSE='OUT';
    'OUT2':
      PIN_NUMBER='(9)';
      OUTPUT_LOAD='(1.0,-1.0)';
      PINUSE='OUT';
    'OUT3':
      PIN_NUMBER='(10)';
      OUTPUT_LOAD='(1.0,-1.0)';
      PINUSE='OUT';
    'GND_2':
      PIN_NUMBER='(11)';
      PINUSE='GROUND';
      NO_LOAD_CHECK='Both';
      NO_IO_CHECK='Both';
      NO_ASSERT_CHECK='TRUE';
      NO_DIR_CHECK='TRUE';
      ALLOW_CONNECT='TRUE';
    'OUT4':
      PIN_NUMBER='(12)';
      OUTPUT_LOAD='(1.0,-1.0)';
      PINUSE='OUT';
    'OUT5':
      PIN_NUMBER='(13)';
      OUTPUT_LOAD='(1.0,-1.0)';
      PINUSE='OUT';
    'OUT6':
      PIN_NUMBER='(14)';
      OUTPUT_LOAD='(1.0,-1.0)';
      PINUSE='OUT';
    'OUT7':
      PIN_NUMBER='(15)';
      OUTPUT_LOAD='(1.0,-1.0)';
      PINUSE='OUT';
    'OUT8':
      PIN_NUMBER='(16)';
      OUTPUT_LOAD='(1.0,-1.0)';
      PINUSE='OUT';
    'OUT9':
      PIN_NUMBER='(17)';
      OUTPUT_LOAD='(1.0,-1.0)';
      PINUSE='OUT';
    'GND_3':
      PIN_NUMBER='(18)';
      PINUSE='GROUND';
      NO_LOAD_CHECK='Both';
      NO_IO_CHECK='Both';
      NO_ASSERT_CHECK='TRUE';
      NO_DIR_CHECK='TRUE';
      ALLOW_CONNECT='TRUE';
    'OUT10':
      PIN_NUMBER='(19)';
      OUTPUT_LOAD='(1.0,-1.0)';
      PINUSE='OUT';
    'OUT11':
      PIN_NUMBER='(20)';
      OUTPUT_LOAD='(1.0,-1.0)';
      PINUSE='OUT';
    'OUT12':
      PIN_NUMBER='(21)';
      OUTPUT_LOAD='(1.0,-1.0)';
      PINUSE='OUT';
    'OUT13':
      PIN_NUMBER='(22)';
      OUTPUT_LOAD='(1.0,-1.0)';
      PINUSE='OUT';
    'OUT14':
      PIN_NUMBER='(23)';
      OUTPUT_LOAD='(1.0,-1.0)';
      PINUSE='OUT';
    'OUT15':
      PIN_NUMBER='(24)';
      OUTPUT_LOAD='(1.0,-1.0)';
      PINUSE='OUT';
    'GND_4':
      PIN_NUMBER='(25)';
      PINUSE='GROUND';
      NO_LOAD_CHECK='Both';
      NO_IO_CHECK='Both';
      NO_ASSERT_CHECK='TRUE';
      NO_DIR_CHECK='TRUE';
      ALLOW_CONNECT='TRUE';
    'OUT16':
      PIN_NUMBER='(26)';
      OUTPUT_LOAD='(1.0,-1.0)';
      PINUSE='OUT';
    'OUT17':
      PIN_NUMBER='(27)';
      OUTPUT_LOAD='(1.0,-1.0)';
      PINUSE='OUT';
    'OUT18':
      PIN_NUMBER='(28)';
      OUTPUT_LOAD='(1.0,-1.0)';
      PINUSE='OUT';
    'THRM_PAD':
      PIN_NUMBER='(29)';
      PINUSE='GROUND';
      NO_LOAD_CHECK='Both';
      NO_IO_CHECK='Both';
      NO_ASSERT_CHECK='TRUE';
      NO_DIR_CHECK='TRUE';
      ALLOW_CONNECT='TRUE';
  end_pin;
  body
      PART_NAME='IS32FL3207_QWLA3_TR_QFN29';
      BODY_NAME='IS32FL3207_QWLA3_TR_QFN29';
      PHYS_DES_PREFIX='U';
      CLASS='IC';
      JEDEC_TYPE='QFN29_197_P0197_TR115SQ_V1';
      ALT_SYMBOLS='(QFN29_197_P0197_TR115SQ_V1)';
      DESCRIPTION='IC,18-CHANNEL LED DRIVER WITH 16-BIT PWM,WFQFN-28';
      CPN_STATUS='';
      PARENT_PART_TYPE='IS32FL3207_QWLA3_TR_QFN29';
      PARENT_PPT='IS32FL3207_QWLA3_TR_QFN29';
      PARENT_PPT_PART='IS32FL3207_QWLA3_TR_QFN29-A223-00002-FB,IS32FL3207-QWLA3-TR';
  end_body;
end_primitive;
primitive 'ISL80101IRAJZ_DFN10-G222-10136A';
  pin
    'VOUT_1':
      PIN_NUMBER='(1)';
      OUTPUT_LOAD='(1.0,-1.0)';
      PINUSE='OUT';
    'VOUT_2':
      PIN_NUMBER='(2)';
      OUTPUT_LOAD='(1.0,-1.0)';
      PINUSE='OUT';
    'SENSE/ADJ':
      PIN_NUMBER='(3)';
      OUTPUT_TYPE='(TS,TS)';
      BIDIRECTIONAL='TRUE';
      INPUT_LOAD='(-0.01,0.01)';
      OUTPUT_LOAD='(1.0,-1.0)';
      PINUSE='BI';
    'PG':
      PIN_NUMBER='(4)';
      OUTPUT_TYPE='(TS,TS)';
      BIDIRECTIONAL='TRUE';
      INPUT_LOAD='(-0.01,0.01)';
      OUTPUT_LOAD='(1.0,-1.0)';
      PINUSE='BI';
    'GND':
      PIN_NUMBER='(5)';
      PINUSE='GROUND';
      NO_LOAD_CHECK='Both';
      NO_IO_CHECK='Both';
      NO_ASSERT_CHECK='TRUE';
      NO_DIR_CHECK='TRUE';
      ALLOW_CONNECT='TRUE';
    'SS':
      PIN_NUMBER='(6)';
      OUTPUT_TYPE='(TS,TS)';
      BIDIRECTIONAL='TRUE';
      INPUT_LOAD='(-0.01,0.01)';
      OUTPUT_LOAD='(1.0,-1.0)';
      PINUSE='BI';
    'ENABLE':
      PIN_NUMBER='(7)';
      OUTPUT_TYPE='(TS,TS)';
      BIDIRECTIONAL='TRUE';
      INPUT_LOAD='(-0.01,0.01)';
      OUTPUT_LOAD='(1.0,-1.0)';
      PINUSE='BI';
    'NC':
      PIN_NUMBER='(8)';
      PINUSE='NC';
      NO_LOAD_CHECK='Both';
      NO_IO_CHECK='Both';
      NO_ASSERT_CHECK='TRUE';
      NO_DIR_CHECK='TRUE';
      ALLOW_CONNECT='TRUE';
    'VIN_1':
      PIN_NUMBER='(9)';
      INPUT_LOAD='(-0.01,0.01)';
      PINUSE='IN';
    'VIN_2':
      PIN_NUMBER='(10)';
      INPUT_LOAD='(-0.01,0.01)';
      PINUSE='IN';
    'THRM_PAD':
      PIN_NUMBER='(11)';
      PINUSE='GROUND';
      NO_LOAD_CHECK='Both';
      NO_IO_CHECK='Both';
      NO_ASSERT_CHECK='TRUE';
      NO_DIR_CHECK='TRUE';
      ALLOW_CONNECT='TRUE';
  end_pin;
  body
      PART_NAME='ISL80101IRAJZ_DFN10';
      BODY_NAME='ISL80101IRAJZ_DFN10';
      PHYS_DES_PREFIX='U';
      CLASS='IC';
      JEDEC_TYPE='DFN11_118_P0197_TR057X071';
      ALT_SYMBOLS='(DFN11_118_P0197_TR057X071_VIA,DFN11_118_P0197_TR065X080_AWS)~
';
      DESCRIPTION='IC,ISL80101IRAJZ-T,LDO,1A,ADJ_REGULATOR,10 LD 3*3 DFN';
      CPN_STATUS='';
      PARENT_PART_TYPE='ISL80101IRAJZ_DFN10';
      PARENT_PPT='ISL80101IRAJZ_DFN10';
      PARENT_PPT_PART='ISL80101IRAJZ_DFN10-G222-10136-01';
  end_body;
end_primitive;
primitive 'LED_4P_V14-G170-10189-01';
  pin
    '4':
      PIN_NUMBER='(4)';
      OUTPUT_TYPE='(TS,TS)';
      BIDIRECTIONAL='TRUE';
      INPUT_LOAD='(-0.01,0.01)';
      OUTPUT_LOAD='(1.0,-1.0)';
      PINUSE='BI';
    '3':
      PIN_NUMBER='(3)';
      OUTPUT_TYPE='(TS,TS)';
      BIDIRECTIONAL='TRUE';
      INPUT_LOAD='(-0.01,0.01)';
      OUTPUT_LOAD='(1.0,-1.0)';
      PINUSE='BI';
    '1':
      PIN_NUMBER='(1)';
      OUTPUT_TYPE='(TS,TS)';
      BIDIRECTIONAL='TRUE';
      INPUT_LOAD='(-0.01,0.01)';
      OUTPUT_LOAD='(1.0,-1.0)';
      PINUSE='BI';
    '2':
      PIN_NUMBER='(2)';
      OUTPUT_TYPE='(TS,TS)';
      BIDIRECTIONAL='TRUE';
      INPUT_LOAD='(-0.01,0.01)';
      OUTPUT_LOAD='(1.0,-1.0)';
      PINUSE='BI';
  end_pin;
  body
      PART_NAME='LED_4P_V14';
      BODY_NAME='LED_4P_V14';
      PHYS_DES_PREFIX='DS';
      CLASS='DISCRETE';
      JEDEC_TYPE='SMC_DS4_098X039';
      ALT_SYMBOLS='(SMC_DS4_098X039)';
      DESCRIPTION='LED,BLUE/RED/GREEN,465/621/525NM,3.3/2/3.3V,20MA,65/110/400MC~
D,2.5X0.7MM,RA,SMD';
      PARENT_PART_TYPE='LED_4P_V14';
      PARENT_PPT='LED_4P_V14';
      PARENT_PPT_PART='LED_4P_V14-G170-10189-01';
  end_body;
end_primitive;
primitive 'LM75BDP_TSSOP8-G220-10215-01';
  pin
    'SDA':
      PIN_NUMBER='(1,0)';
      OUTPUT_TYPE='(TS,TS)';
      BIDIRECTIONAL='TRUE';
      INPUT_LOAD='(-0.01,0.01)';
      OUTPUT_LOAD='(1.0,-1.0)';
      PINUSE='BI';
    'SCL':
      PIN_NUMBER='(2,0)';
      INPUT_LOAD='(-0.01,0.01)';
      PINUSE='IN';
    'OS':
      PIN_NUMBER='(3,0)';
      OUTPUT_LOAD='(1.0,-1.0)';
      PINUSE='OUT';
    'A2':
      PIN_NUMBER='(5,0)';
      INPUT_LOAD='(-0.01,0.01)';
      PINUSE='IN';
    'A1':
      PIN_NUMBER='(6,0)';
      INPUT_LOAD='(-0.01,0.01)';
      PINUSE='IN';
    'A0':
      PIN_NUMBER='(7,0)';
      INPUT_LOAD='(-0.01,0.01)';
      PINUSE='IN';
    'VCC':
      PIN_NUMBER='(0,8)';
      PINUSE='POWER';
      NO_LOAD_CHECK='Both';
      NO_IO_CHECK='Both';
      NO_ASSERT_CHECK='TRUE';
      NO_DIR_CHECK='TRUE';
      ALLOW_CONNECT='TRUE';
    'GND':
      PIN_NUMBER='(0,4)';
      PINUSE='GROUND';
      NO_LOAD_CHECK='Both';
      NO_IO_CHECK='Both';
      NO_ASSERT_CHECK='TRUE';
      NO_DIR_CHECK='TRUE';
      ALLOW_CONNECT='TRUE';
  end_pin;
  body
      PART_NAME='LM75BDP_TSSOP8';
      BODY_NAME='LM75BDP_TSSOP8';
      PHYS_DES_PREFIX='U';
      CLASS='IC';
      JEDEC_TYPE='SOP8_118_P0256_V2';
      ALT_SYMBOLS='(SOP8_118_P0256_V2)';
      DESCRIPTION='IC, LM75B, I2C TEMP SENSOR, TSSOP8';
      PARENT_PART_TYPE='LM75BDP_TSSOP8';
      PARENT_PPT='LM75BDP_TSSOP8';
      PARENT_PPT_PART='LM75BDP_TSSOP8-G220-10215-01';
  end_body;
end_primitive;
primitive 'MEC_MTH8-MTH125C236N_V8-MTH125A';
  pin
    '2':
      PIN_NUMBER='(2)';
      PINUSE='UNSPEC';
      NO_LOAD_CHECK='Both';
      NO_IO_CHECK='Both';
      ALLOW_CONNECT='TRUE';
    '3':
      PIN_NUMBER='(3)';
      PINUSE='UNSPEC';
      NO_LOAD_CHECK='Both';
      NO_IO_CHECK='Both';
      ALLOW_CONNECT='TRUE';
    '1':
      PIN_NUMBER='(1)';
      PINUSE='UNSPEC';
      NO_LOAD_CHECK='Both';
      NO_IO_CHECK='Both';
      ALLOW_CONNECT='TRUE';
    '4':
      PIN_NUMBER='(4)';
      PINUSE='UNSPEC';
      NO_LOAD_CHECK='Both';
      NO_IO_CHECK='Both';
      ALLOW_CONNECT='TRUE';
    '6':
      PIN_NUMBER='(6)';
      PINUSE='UNSPEC';
      NO_LOAD_CHECK='Both';
      NO_IO_CHECK='Both';
      ALLOW_CONNECT='TRUE';
    '5':
      PIN_NUMBER='(5)';
      PINUSE='UNSPEC';
      NO_LOAD_CHECK='Both';
      NO_IO_CHECK='Both';
      ALLOW_CONNECT='TRUE';
    '7':
      PIN_NUMBER='(7)';
      PINUSE='UNSPEC';
      NO_LOAD_CHECK='Both';
      NO_IO_CHECK='Both';
      ALLOW_CONNECT='TRUE';
    '8':
      PIN_NUMBER='(8)';
      PINUSE='UNSPEC';
      NO_LOAD_CHECK='Both';
      NO_IO_CHECK='Both';
      ALLOW_CONNECT='TRUE';
  end_pin;
  body
      PART_NAME='MEC_MTH8';
      BODY_NAME='MEC_MTH8';
      TEC='TERM';
      UNKNOWN_LOADING='TRUE';
      PHYS_DES_PREFIX='ME';
      CLASS='IO';
      JEDEC_TYPE='MTH125C236N_V8';
      PARENT_PART_TYPE='MEC_MTH8';
      SCH_MODIFIED_PART='TRUE';
      PARENT_PPT='MEC_MTH8';
      PARENT_PPT_PART='MEC_MTH8-MTH125C236N_V8';
  end_body;
end_primitive;
primitive 'MEC_NPTH-MTH100C240N-MTH100C24A';
  pin
  end_pin;
  body
      PART_NAME='MEC_NPTH';
      BODY_NAME='MEC_NPTH';
      PHYS_DES_PREFIX='ME';
      CLASS='MECHANICAL';
      JEDEC_TYPE='MTH100C240N';
      PARENT_PART_TYPE='MEC_NPTH';
      SCH_MODIFIED_PART='TRUE';
      PARENT_PPT='MEC_NPTH';
      PARENT_PPT_PART='MEC_NPTH-MTH100C240N';
  end_body;
end_primitive;
primitive 'MP5022CGQV_Z_QFN22-G220-10510-A';
  pin
    'EN':
      PIN_NUMBER='(1)';
      INPUT_LOAD='(-0.01,0.01)';
      PINUSE='IN';
    'LOADEN':
      PIN_NUMBER='(2)';
      INPUT_LOAD='(-0.01,0.01)';
      PINUSE='IN';
    'ENTM':
      PIN_NUMBER='(3)';
      OUTPUT_TYPE='(TS,TS)';
      BIDIRECTIONAL='TRUE';
      INPUT_LOAD='(-0.01,0.01)';
      OUTPUT_LOAD='(1.0,-1.0)';
      PINUSE='BI';
    'TIMER':
      PIN_NUMBER='(4)';
      OUTPUT_TYPE='(TS,TS)';
      BIDIRECTIONAL='TRUE';
      INPUT_LOAD='(-0.01,0.01)';
      OUTPUT_LOAD='(1.0,-1.0)';
      PINUSE='BI';
    'ISET':
      PIN_NUMBER='(5)';
      OUTPUT_TYPE='(TS,TS)';
      BIDIRECTIONAL='TRUE';
      INPUT_LOAD='(-0.01,0.01)';
      OUTPUT_LOAD='(1.0,-1.0)';
      PINUSE='BI';
    'SS':
      PIN_NUMBER='(6)';
      OUTPUT_TYPE='(TS,TS)';
      BIDIRECTIONAL='TRUE';
      INPUT_LOAD='(-0.01,0.01)';
      OUTPUT_LOAD='(1.0,-1.0)';
      PINUSE='BI';
    'GND':
      PIN_NUMBER='(7)';
      PINUSE='GROUND';
      NO_LOAD_CHECK='Both';
      NO_IO_CHECK='Both';
      NO_ASSERT_CHECK='TRUE';
      NO_DIR_CHECK='TRUE';
      ALLOW_CONNECT='TRUE';
    'IMON':
      PIN_NUMBER='(8)';
      OUTPUT_LOAD='(1.0,-1.0)';
      PINUSE='OUT';
    'FLTB':
      PIN_NUMBER='(9)';
      OUTPUT_LOAD='(1.0,-1.0)';
      PINUSE='OUT';
    'PG':
      PIN_NUMBER='(10)';
      OUTPUT_LOAD='(1.0,-1.0)';
      PINUSE='OUT';
    'OV':
      PIN_NUMBER='(11)';
      INPUT_LOAD='(-0.01,0.01)';
      PINUSE='IN';
    'AVIN':
      PIN_NUMBER='(12)';
      PINUSE='POWER';
    'VOUT_1':
      PIN_NUMBER='(13)';
      OUTPUT_LOAD='(1.0,-1.0)';
      PINUSE='OUT';
    'VOUT_2':
      PIN_NUMBER='(14)';
      OUTPUT_LOAD='(1.0,-1.0)';
      PINUSE='OUT';
    'VOUT_3':
      PIN_NUMBER='(15)';
      OUTPUT_LOAD='(1.0,-1.0)';
      PINUSE='OUT';
    'VOUT_4':
      PIN_NUMBER='(16)';
      OUTPUT_LOAD='(1.0,-1.0)';
      PINUSE='OUT';
    'VOUT_5':
      PIN_NUMBER='(17)';
      OUTPUT_LOAD='(1.0,-1.0)';
      PINUSE='OUT';
    'VOUT_6':
      PIN_NUMBER='(18)';
      OUTPUT_LOAD='(1.0,-1.0)';
      PINUSE='OUT';
    'VOUT_7':
      PIN_NUMBER='(19)';
      OUTPUT_LOAD='(1.0,-1.0)';
      PINUSE='OUT';
    'VOUT_8':
      PIN_NUMBER='(20)';
      OUTPUT_LOAD='(1.0,-1.0)';
      PINUSE='OUT';
    'VIN_1':
      PIN_NUMBER='(21)';
      PINUSE='POWER';
      NO_LOAD_CHECK='Both';
      NO_IO_CHECK='Both';
      NO_ASSERT_CHECK='TRUE';
      NO_DIR_CHECK='TRUE';
      ALLOW_CONNECT='TRUE';
    'VIN_2':
      PIN_NUMBER='(22)';
      PINUSE='POWER';
    'VIN_3':
      PIN_NUMBER='(23)';
      PINUSE='POWER';
    'VIN_4':
      PIN_NUMBER='(24)';
      PINUSE='POWER';
    'VIN_5':
      PIN_NUMBER='(25)';
      PINUSE='POWER';
    'VIN_6':
      PIN_NUMBER='(26)';
      PINUSE='POWER';
  end_pin;
  body
      PART_NAME='MP5022CGQV_Z_QFN22';
      BODY_NAME='MP5022CGQV_Z_QFN22';
      PHYS_DES_PREFIX='U';
      CLASS='IC';
      JEDEC_TYPE='QFN26_118X197_P197_TR049X010';
      ALT_SYMBOLS='(QFN26_118X197_P197_TR049X010)';
      DESCRIPTION='IC,MP5022C,HOTSWAP,15A,3MMX5MM,QFN-22';
      PARENT_PART_TYPE='MP5022CGQV_Z_QFN22';
      PARENT_PPT='MP5022CGQV_Z_QFN22';
      PARENT_PPT_PART='MP5022CGQV_Z_QFN22-G220-10510-01';
  end_body;
end_primitive;
primitive 'MT25QL128ABA1ESE_SOP8-G221-102A';
  pin
    'S*':
      PIN_NUMBER='(1)';
      INPUT_LOAD='(-0.01,0.01)';
      PINUSE='IN';
    'DQ1':
      PIN_NUMBER='(2)';
      OUTPUT_TYPE='(TS,TS)';
      BIDIRECTIONAL='TRUE';
      INPUT_LOAD='(-0.01,0.01)';
      OUTPUT_LOAD='(1.0,-1.0)';
      PINUSE='BI';
    'W/DQ2*':
      PIN_NUMBER='(3)';
      OUTPUT_TYPE='(TS,TS)';
      BIDIRECTIONAL='TRUE';
      INPUT_LOAD='(-0.01,0.01)';
      OUTPUT_LOAD='(1.0,-1.0)';
      PINUSE='BI';
    'VSS':
      PIN_NUMBER='(4)';
      PINUSE='GROUND';
      NO_LOAD_CHECK='Both';
      NO_IO_CHECK='Both';
      NO_ASSERT_CHECK='TRUE';
      NO_DIR_CHECK='TRUE';
      ALLOW_CONNECT='TRUE';
    'DQ0':
      PIN_NUMBER='(5)';
      OUTPUT_TYPE='(TS,TS)';
      BIDIRECTIONAL='TRUE';
      INPUT_LOAD='(-0.01,0.01)';
      OUTPUT_LOAD='(1.0,-1.0)';
      PINUSE='BI';
    'C':
      PIN_NUMBER='(6)';
      INPUT_LOAD='(-0.01,0.01)';
      PINUSE='IN';
    'HOLD/DQ3*':
      PIN_NUMBER='(7)';
      OUTPUT_TYPE='(TS,TS)';
      BIDIRECTIONAL='TRUE';
      INPUT_LOAD='(-0.01,0.01)';
      OUTPUT_LOAD='(1.0,-1.0)';
      PINUSE='BI';
    'VCC':
      PIN_NUMBER='(8)';
      PINUSE='POWER';
      NO_LOAD_CHECK='Both';
      NO_IO_CHECK='Both';
      NO_ASSERT_CHECK='TRUE';
      NO_DIR_CHECK='TRUE';
      ALLOW_CONNECT='TRUE';
  end_pin;
  body
      PART_NAME='MT25QL128ABA1ESE_SOP8';
      BODY_NAME='MT25QL128ABA1ESE_SOP8';
      PHYS_DES_PREFIX='U';
      CLASS='IC';
      JEDEC_TYPE='SOP8_208_P050_V2';
      ALT_SYMBOLS='(SOP8_208_P050_V2)';
      DESCRIPTION='IC,FLASH,128MBIT,2.7V-3.6V,SO8W';
      CPN_STATUS='';
      PARENT_PART_TYPE='MT25QL128ABA1ESE_SOP8';
      PARENT_PPT='MT25QL128ABA1ESE_SOP8';
      PARENT_PPT_PART='MT25QL128ABA1ESE_SOP8-G221-10224-01,MT25QL128ABA1ESE-0SIT';
  end_body;
end_primitive;
primitive 'NCP45560IMNTWG_H_DFN12-G222-10A';
  pin
    'VIN_1':
      PIN_NUMBER='(1,0)';
      OUTPUT_TYPE='(TS,TS)';
      BIDIRECTIONAL='TRUE';
      INPUT_LOAD='(-0.01,0.01)';
      OUTPUT_LOAD='(1.0,-1.0)';
      PINUSE='BI';
    'EN':
      PIN_NUMBER='(2,0)';
      OUTPUT_TYPE='(TS,TS)';
      BIDIRECTIONAL='TRUE';
      INPUT_LOAD='(-0.01,0.01)';
      OUTPUT_LOAD='(1.0,-1.0)';
      PINUSE='BI';
    'SR':
      PIN_NUMBER='(5,0)';
      OUTPUT_TYPE='(TS,TS)';
      BIDIRECTIONAL='TRUE';
      INPUT_LOAD='(-0.01,0.01)';
      OUTPUT_LOAD='(1.0,-1.0)';
      PINUSE='BI';
    'PG':
      PIN_NUMBER='(6,0)';
      OUTPUT_TYPE='(TS,TS)';
      BIDIRECTIONAL='TRUE';
      INPUT_LOAD='(-0.01,0.01)';
      OUTPUT_LOAD='(1.0,-1.0)';
      PINUSE='BI';
    'BLEED':
      PIN_NUMBER='(7,0)';
      OUTPUT_TYPE='(TS,TS)';
      BIDIRECTIONAL='TRUE';
      INPUT_LOAD='(-0.01,0.01)';
      OUTPUT_LOAD='(1.0,-1.0)';
      PINUSE='BI';
    'VOUT_1':
      PIN_NUMBER='(8,0)';
      OUTPUT_TYPE='(TS,TS)';
      BIDIRECTIONAL='TRUE';
      INPUT_LOAD='(-0.01,0.01)';
      OUTPUT_LOAD='(1.0,-1.0)';
      PINUSE='BI';
    'VOUT_2':
      PIN_NUMBER='(9,0)';
      OUTPUT_TYPE='(TS,TS)';
      BIDIRECTIONAL='TRUE';
      INPUT_LOAD='(-0.01,0.01)';
      OUTPUT_LOAD='(1.0,-1.0)';
      PINUSE='BI';
    'VOUT_3':
      PIN_NUMBER='(10,0)';
      OUTPUT_TYPE='(TS,TS)';
      BIDIRECTIONAL='TRUE';
      INPUT_LOAD='(-0.01,0.01)';
      OUTPUT_LOAD='(1.0,-1.0)';
      PINUSE='BI';
    'VOUT_4':
      PIN_NUMBER='(11,0)';
      OUTPUT_TYPE='(TS,TS)';
      BIDIRECTIONAL='TRUE';
      INPUT_LOAD='(-0.01,0.01)';
      OUTPUT_LOAD='(1.0,-1.0)';
      PINUSE='BI';
    'VOUT_5':
      PIN_NUMBER='(12,0)';
      OUTPUT_TYPE='(TS,TS)';
      BIDIRECTIONAL='TRUE';
      INPUT_LOAD='(-0.01,0.01)';
      OUTPUT_LOAD='(1.0,-1.0)';
      PINUSE='BI';
    'VIN_2':
      PIN_NUMBER='(13,0)';
      OUTPUT_TYPE='(TS,TS)';
      BIDIRECTIONAL='TRUE';
      INPUT_LOAD='(-0.01,0.01)';
      OUTPUT_LOAD='(1.0,-1.0)';
      PINUSE='BI';
    'VCC':
      PIN_NUMBER='(0,3)';
      PINUSE='POWER';
      NO_LOAD_CHECK='Both';
      NO_IO_CHECK='Both';
      NO_ASSERT_CHECK='TRUE';
      NO_DIR_CHECK='TRUE';
      ALLOW_CONNECT='TRUE';
    'GND':
      PIN_NUMBER='(0,4)';
      PINUSE='GROUND';
      NO_LOAD_CHECK='Both';
      NO_IO_CHECK='Both';
      NO_ASSERT_CHECK='TRUE';
      NO_DIR_CHECK='TRUE';
      ALLOW_CONNECT='TRUE';
  end_pin;
  body
      PART_NAME='NCP45560IMNTWG_H_DFN12';
      BODY_NAME='NCP45560IMNTWG_H_DFN12';
      PHYS_DES_PREFIX='U';
      CLASS='IC';
      JEDEC_TYPE='DFN13_118_P0197_TR071X096';
      ALT_SYMBOLS='(DFN13_118_P0197_TR071X096_AWS,DFN13_118_P0197_TR071X096_VIA)~
';
      DESCRIPTION='IC,NCP45560-H,ECOSWITCH,0.5-13.5VIN,DFN12';
      PARENT_PART_TYPE='NCP45560IMNTWG_H_DFN12';
      PARENT_PPT='NCP45560IMNTWG_H_DFN12';
      PARENT_PPT_PART='NCP45560IMNTWG_H_DFN12-G222-10203-01';
  end_body;
end_primitive;
primitive 'NLASB3157DFT2G_SC88-G223-10187A';
  pin
    'B1':
      PIN_NUMBER='(1,0)';
      OUTPUT_TYPE='(TS,TS)';
      BIDIRECTIONAL='TRUE';
      INPUT_LOAD='(-0.01,0.01)';
      OUTPUT_LOAD='(1.0,-1.0)';
      PINUSE='BI';
    'B0':
      PIN_NUMBER='(3,0)';
      OUTPUT_TYPE='(TS,TS)';
      BIDIRECTIONAL='TRUE';
      INPUT_LOAD='(-0.01,0.01)';
      OUTPUT_LOAD='(1.0,-1.0)';
      PINUSE='BI';
    'A':
      PIN_NUMBER='(4,0)';
      OUTPUT_TYPE='(TS,TS)';
      BIDIRECTIONAL='TRUE';
      INPUT_LOAD='(-0.01,0.01)';
      OUTPUT_LOAD='(1.0,-1.0)';
      PINUSE='BI';
    'SELECT':
      PIN_NUMBER='(6,0)';
      OUTPUT_TYPE='(TS,TS)';
      BIDIRECTIONAL='TRUE';
      INPUT_LOAD='(-0.01,0.01)';
      OUTPUT_LOAD='(1.0,-1.0)';
      PINUSE='BI';
    'GND':
      PIN_NUMBER='(0,2)';
      PINUSE='GROUND';
      NO_LOAD_CHECK='Both';
      NO_IO_CHECK='Both';
      NO_ASSERT_CHECK='TRUE';
      NO_DIR_CHECK='TRUE';
      ALLOW_CONNECT='TRUE';
    'VCC':
      PIN_NUMBER='(0,5)';
      PINUSE='POWER';
      NO_LOAD_CHECK='Both';
      NO_IO_CHECK='Both';
      NO_ASSERT_CHECK='TRUE';
      NO_DIR_CHECK='TRUE';
      ALLOW_CONNECT='TRUE';
  end_pin;
  body
      PART_NAME='NLASB3157DFT2G_SC88';
      BODY_NAME='NLASB3157DFT2G_SC88';
      PHYS_DES_PREFIX='U';
      CLASS='IC';
      JEDEC_TYPE='SOT363_V2';
      ALT_SYMBOLS='(SOT363_V2)';
      DESCRIPTION='IC,2:1 MULTIPLEXER,CMOS ANALOG SWITCH,6P,SOT-363';
      PARENT_PART_TYPE='NLASB3157DFT2G_SC88';
      PARENT_PPT='NLASB3157DFT2G_SC88';
      PARENT_PPT_PART='NLASB3157DFT2G_SC88-G223-10187-01';
  end_body;
end_primitive;
primitive 'NULL-G380-10013-01';
  pin
  end_pin;
  body
      PART_NAME='NULL';
      BODY_NAME='NULL';
      JEDEC_TYPE='DUMMY';
      PHYS_DES_PREFIX='ME';
      CLASS='MECHANICAL';
      DESCRIPTION='ALPHA,SOLDER PREFORM,ALLOY SAC305,0603H';
      CPN_STATUS='';
      PARENT_PART_TYPE='NULL';
      PARENT_PPT='NULL';
      PARENT_PPT_PART='NULL-G380-10013-01';
  end_body;
end_primitive;
primitive 'NUT-A200-00029-FB';
  pin
    '1':
      PIN_NUMBER='(1)';
      PINUSE='UNSPEC';
      NO_LOAD_CHECK='Both';
      NO_IO_CHECK='Both';
      ALLOW_CONNECT='TRUE';
  end_pin;
  body
      PART_NAME='NUT';
      BODY_NAME='NUT';
      TEC='TERM';
      UNKNOWN_LOADING='TRUE';
      PHYS_DES_PREFIX='ME';
      CLASS='IO';
      JEDEC_TYPE='P_NUT_079C100';
      ALT_SYMBOLS='(P_NUT_079C100)';
      DESCRIPTION='CON,1P,RECEPTACLE WITH OFP SOLDER BARRIER,DIA 0.940MM-1.092MM~
';
      CPN_STATUS='';
      PARENT_PART_TYPE='NUT';
      PARENT_PPT='NUT';
      PARENT_PPT_PART='NUT-A200-00029-FB';
  end_body;
end_primitive;
primitive 'NUT-G340-10437-01';
  pin
    '1':
      PIN_NUMBER='(1)';
      PINUSE='UNSPEC';
      NO_LOAD_CHECK='Both';
      NO_IO_CHECK='Both';
      ALLOW_CONNECT='TRUE';
  end_pin;
  body
      PART_NAME='NUT';
      BODY_NAME='NUT';
      TEC='TERM';
      UNKNOWN_LOADING='TRUE';
      PHYS_DES_PREFIX='ME';
      CLASS='IO';
      JEDEC_TYPE='P_NUT_166CT244CB198_V1_H380';
      ALT_SYMBOLS='(P_NUT_166CT244CB198_V1_H380)';
      DESCRIPTION='HDW,SMT STANDOFF,#4-40,L.375';
      CPN_STATUS='';
      PARENT_PART_TYPE='NUT';
      PARENT_PPT='NUT';
      PARENT_PPT_PART='NUT-G340-10437-01';
  end_body;
end_primitive;
primitive 'OPTICAL-G170-10143-01';
  pin
    'A':
      PIN_NUMBER='(A)';
      OUTPUT_TYPE='(TS,TS)';
      BIDIRECTIONAL='TRUE';
      INPUT_LOAD='(-0.01,0.01)';
      OUTPUT_LOAD='(1.0,-1.0)';
      PINUSE='BI';
    'C':
      PIN_NUMBER='(C)';
      OUTPUT_TYPE='(TS,TS)';
      BIDIRECTIONAL='TRUE';
      INPUT_LOAD='(-0.01,0.01)';
      OUTPUT_LOAD='(1.0,-1.0)';
      PINUSE='BI';
  end_pin;
  body
      PART_NAME='OPTICAL';
      BODY_NAME='OPTICAL';
      PHYS_DES_PREFIX='DS';
      CLASS='DISCRETE';
      JEDEC_TYPE='SMC_DS_063X031_V4';
      ALT_SYMBOLS='(SMC_DS_063X031_V4)';
      DESCRIPTION='LED,GREEN,UPPER LIGHT,571NM,5V,30MA,35MCD,SMT';
      CPN_STATUS='';
      PARENT_PART_TYPE='OPTICAL';
      PARENT_PPT='OPTICAL';
      PARENT_PPT_PART='OPTICAL-G170-10143-01';
  end_body;
end_primitive;
primitive 'OSC6P_V2-A130-00003-AW';
  pin
    'OE':
      PIN_NUMBER='(1)';
      INPUT_LOAD='(-0.01,0.01)';
      PINUSE='IN';
    'NC':
      PIN_NUMBER='(2)';
      PINUSE='NC';
      NO_LOAD_CHECK='Both';
      NO_IO_CHECK='Both';
      NO_ASSERT_CHECK='TRUE';
      NO_DIR_CHECK='TRUE';
      ALLOW_CONNECT='TRUE';
    'GND':
      PIN_NUMBER='(3)';
      PINUSE='GROUND';
      NO_LOAD_CHECK='Both';
      NO_IO_CHECK='Both';
      NO_ASSERT_CHECK='TRUE';
      NO_DIR_CHECK='TRUE';
      ALLOW_CONNECT='TRUE';
    'OUT_P':
      PIN_NUMBER='(4)';
      OUTPUT_LOAD='(1.0,-1.0)';
      PINUSE='OUT';
    'OUT_N':
      PIN_NUMBER='(5)';
      OUTPUT_LOAD='(1.0,-1.0)';
      PINUSE='OUT';
    'VDD':
      PIN_NUMBER='(6)';
      PINUSE='POWER';
      NO_LOAD_CHECK='Both';
      NO_IO_CHECK='Both';
      NO_ASSERT_CHECK='TRUE';
      NO_DIR_CHECK='TRUE';
      ALLOW_CONNECT='TRUE';
  end_pin;
  body
      PART_NAME='OSC6P_V2';
      BODY_NAME='OSC6P_V2';
      PHYS_DES_PREFIX='Y';
      CLASS='DISCRETE';
      JEDEC_TYPE='SMC_Y6_126X197';
      ALT_SYMBOLS='(SMC_Y6_126X197)';
      DESCRIPTION='OSC,5032 XO,200MHZ,+-50PPM,3.3V,150FS,LVDS QFM6,SMT';
      CPN_STATUS='';
      PARENT_PART_TYPE='OSC6P_V2';
      PARENT_PPT='OSC6P_V2';
      PARENT_PPT_PART='OSC6P_V2-A130-00003-AW';
  end_body;
end_primitive;
primitive 'OSC6P_V2-A130-00004-AW';
  pin
    'OE':
      PIN_NUMBER='(1)';
      INPUT_LOAD='(-0.01,0.01)';
      PINUSE='IN';
    'NC':
      PIN_NUMBER='(2)';
      PINUSE='NC';
      NO_LOAD_CHECK='Both';
      NO_IO_CHECK='Both';
      NO_ASSERT_CHECK='TRUE';
      NO_DIR_CHECK='TRUE';
      ALLOW_CONNECT='TRUE';
    'GND':
      PIN_NUMBER='(3)';
      PINUSE='GROUND';
      NO_LOAD_CHECK='Both';
      NO_IO_CHECK='Both';
      NO_ASSERT_CHECK='TRUE';
      NO_DIR_CHECK='TRUE';
      ALLOW_CONNECT='TRUE';
    'OUT_P':
      PIN_NUMBER='(4)';
      OUTPUT_LOAD='(1.0,-1.0)';
      PINUSE='OUT';
    'OUT_N':
      PIN_NUMBER='(5)';
      OUTPUT_LOAD='(1.0,-1.0)';
      PINUSE='OUT';
    'VDD':
      PIN_NUMBER='(6)';
      PINUSE='POWER';
      NO_LOAD_CHECK='Both';
      NO_IO_CHECK='Both';
      NO_ASSERT_CHECK='TRUE';
      NO_DIR_CHECK='TRUE';
      ALLOW_CONNECT='TRUE';
  end_pin;
  body
      PART_NAME='OSC6P_V2';
      BODY_NAME='OSC6P_V2';
      PHYS_DES_PREFIX='Y';
      CLASS='DISCRETE';
      JEDEC_TYPE='SMC_Y6_197X276';
      ALT_SYMBOLS='(SMC_Y6_197X276)';
      DESCRIPTION='OSC,7050 XO,125MHZ,+-50PPM,3.3V,90FS,LVDS QFM6,SMT';
      CPN_STATUS='';
      PARENT_PART_TYPE='OSC6P_V2';
      PARENT_PPT='OSC6P_V2';
      PARENT_PPT_PART='OSC6P_V2-A130-00004-AW';
  end_body;
end_primitive;
primitive 'PCA9508DP_TSSOP8-G223-10278-01';
  pin
    'SCLA':
      PIN_NUMBER='(2,0)';
      OUTPUT_TYPE='(TS,TS)';
      BIDIRECTIONAL='TRUE';
      INPUT_LOAD='(-0.01,0.01)';
      OUTPUT_LOAD='(1.0,-1.0)';
      PINUSE='BI';
    'SDAA':
      PIN_NUMBER='(3,0)';
      OUTPUT_TYPE='(TS,TS)';
      BIDIRECTIONAL='TRUE';
      INPUT_LOAD='(-0.01,0.01)';
      OUTPUT_LOAD='(1.0,-1.0)';
      PINUSE='BI';
    'EN':
      PIN_NUMBER='(5,0)';
      INPUT_LOAD='(-0.01,0.01)';
      PINUSE='IN';
    'SDAB':
      PIN_NUMBER='(6,0)';
      OUTPUT_TYPE='(TS,TS)';
      BIDIRECTIONAL='TRUE';
      INPUT_LOAD='(-0.01,0.01)';
      OUTPUT_LOAD='(1.0,-1.0)';
      PINUSE='BI';
    'SCLB':
      PIN_NUMBER='(7,0)';
      OUTPUT_TYPE='(TS,TS)';
      BIDIRECTIONAL='TRUE';
      INPUT_LOAD='(-0.01,0.01)';
      OUTPUT_LOAD='(1.0,-1.0)';
      PINUSE='BI';
    'VCC_A':
      PIN_NUMBER='(0,1)';
      PINUSE='POWER';
      NO_LOAD_CHECK='Both';
      NO_IO_CHECK='Both';
      NO_ASSERT_CHECK='TRUE';
      NO_DIR_CHECK='TRUE';
      ALLOW_CONNECT='TRUE';
    'GND':
      PIN_NUMBER='(0,4)';
      PINUSE='GROUND';
      NO_LOAD_CHECK='Both';
      NO_IO_CHECK='Both';
      NO_ASSERT_CHECK='TRUE';
      NO_DIR_CHECK='TRUE';
      ALLOW_CONNECT='TRUE';
    'VCC_B':
      PIN_NUMBER='(0,8)';
      PINUSE='POWER';
      NO_LOAD_CHECK='Both';
      NO_IO_CHECK='Both';
      NO_ASSERT_CHECK='TRUE';
      NO_DIR_CHECK='TRUE';
      ALLOW_CONNECT='TRUE';
  end_pin;
  body
      PART_NAME='PCA9508DP_TSSOP8';
      BODY_NAME='PCA9508DP_TSSOP8';
      PHYS_DES_PREFIX='U';
      CLASS='IC';
      JEDEC_TYPE='SOP8_118_P0256_V2';
      ALT_SYMBOLS='(SOP8_118_P0256_V2)';
      DESCRIPTION='IC,I2C,REPEATER,9617A,0.8~5.5V,2.2~5.5V,MSOP8';
      CPN_STATUS='PREFERRED';
      PARENT_PART_TYPE='PCA9508DP_TSSOP8';
      PARENT_PPT='PCA9508DP_TSSOP8';
      PARENT_PPT_PART='PCA9508DP_TSSOP8-G223-10278-01';
  end_body;
end_primitive;
primitive 'PCA9546APW_TSSOP16-G223-10280-A';
  pin
    'A0':
      PIN_NUMBER='(1,0)';
      INPUT_LOAD='(-0.01,0.01)';
      PINUSE='IN';
    'A1':
      PIN_NUMBER='(2,0)';
      INPUT_LOAD='(-0.01,0.01)';
      PINUSE='IN';
    'RESET*':
      PIN_NUMBER='(3,0)';
      INPUT_LOAD='(-0.01,0.01)';
      PINUSE='IN';
    'SD0':
      PIN_NUMBER='(4,0)';
      OUTPUT_TYPE='(TS,TS)';
      BIDIRECTIONAL='TRUE';
      INPUT_LOAD='(-0.01,0.01)';
      OUTPUT_LOAD='(1.0,-1.0)';
      PINUSE='BI';
    'SC0':
      PIN_NUMBER='(5,0)';
      OUTPUT_TYPE='(TS,TS)';
      BIDIRECTIONAL='TRUE';
      INPUT_LOAD='(-0.01,0.01)';
      OUTPUT_LOAD='(1.0,-1.0)';
      PINUSE='BI';
    'SD1':
      PIN_NUMBER='(6,0)';
      OUTPUT_TYPE='(TS,TS)';
      BIDIRECTIONAL='TRUE';
      INPUT_LOAD='(-0.01,0.01)';
      OUTPUT_LOAD='(1.0,-1.0)';
      PINUSE='BI';
    'SC1':
      PIN_NUMBER='(7,0)';
      OUTPUT_TYPE='(TS,TS)';
      BIDIRECTIONAL='TRUE';
      INPUT_LOAD='(-0.01,0.01)';
      OUTPUT_LOAD='(1.0,-1.0)';
      PINUSE='BI';
    'SD2':
      PIN_NUMBER='(9,0)';
      OUTPUT_TYPE='(TS,TS)';
      BIDIRECTIONAL='TRUE';
      INPUT_LOAD='(-0.01,0.01)';
      OUTPUT_LOAD='(1.0,-1.0)';
      PINUSE='BI';
    'SC2':
      PIN_NUMBER='(10,0)';
      OUTPUT_TYPE='(TS,TS)';
      BIDIRECTIONAL='TRUE';
      INPUT_LOAD='(-0.01,0.01)';
      OUTPUT_LOAD='(1.0,-1.0)';
      PINUSE='BI';
    'SD3':
      PIN_NUMBER='(11,0)';
      OUTPUT_TYPE='(TS,TS)';
      BIDIRECTIONAL='TRUE';
      INPUT_LOAD='(-0.01,0.01)';
      OUTPUT_LOAD='(1.0,-1.0)';
      PINUSE='BI';
    'SC3':
      PIN_NUMBER='(12,0)';
      OUTPUT_TYPE='(TS,TS)';
      BIDIRECTIONAL='TRUE';
      INPUT_LOAD='(-0.01,0.01)';
      OUTPUT_LOAD='(1.0,-1.0)';
      PINUSE='BI';
    'A2':
      PIN_NUMBER='(13,0)';
      INPUT_LOAD='(-0.01,0.01)';
      PINUSE='IN';
    'SCL':
      PIN_NUMBER='(14,0)';
      OUTPUT_TYPE='(TS,TS)';
      BIDIRECTIONAL='TRUE';
      INPUT_LOAD='(-0.01,0.01)';
      OUTPUT_LOAD='(1.0,-1.0)';
      PINUSE='BI';
    'SDA':
      PIN_NUMBER='(15,0)';
      OUTPUT_TYPE='(TS,TS)';
      BIDIRECTIONAL='TRUE';
      INPUT_LOAD='(-0.01,0.01)';
      OUTPUT_LOAD='(1.0,-1.0)';
      PINUSE='BI';
    'VSS':
      PIN_NUMBER='(0,8)';
      PINUSE='GROUND';
      NO_LOAD_CHECK='Both';
      NO_IO_CHECK='Both';
      NO_ASSERT_CHECK='TRUE';
      NO_DIR_CHECK='TRUE';
      ALLOW_CONNECT='TRUE';
    'VDD':
      PIN_NUMBER='(0,16)';
      PINUSE='POWER';
      NO_LOAD_CHECK='Both';
      NO_IO_CHECK='Both';
      NO_ASSERT_CHECK='TRUE';
      NO_DIR_CHECK='TRUE';
      ALLOW_CONNECT='TRUE';
  end_pin;
  body
      PART_NAME='PCA9546APW_TSSOP16';
      BODY_NAME='PCA9546APW_TSSOP16';
      PHYS_DES_PREFIX='U';
      CLASS='IC';
      JEDEC_TYPE='SOP16_173_P0256_H043';
      ALT_SYMBOLS='(SOP16_173_P0256_H043)';
      DESCRIPTION='IC,I2C,4CH SWITCH,9546A,2.3~5.5V,TSSOP16';
      CPN_STATUS='PREFERRED';
      PARENT_PART_TYPE='PCA9546APW_TSSOP16';
      PARENT_PPT='PCA9546APW_TSSOP16';
      PARENT_PPT_PART='PCA9546APW_TSSOP16-G223-10280-01';
  end_body;
end_primitive;
primitive 'POWERMOS_3P_NCH_V1-G121-10200-A';
  pin
    'G':
      PIN_NUMBER='(1)';
      OUTPUT_TYPE='(TS,TS)';
      BIDIRECTIONAL='TRUE';
      INPUT_LOAD='(-0.01,0.01)';
      OUTPUT_LOAD='(1.0,-1.0)';
      PINUSE='BI';
    'S':
      PIN_NUMBER='(2)';
      OUTPUT_TYPE='(TS,TS)';
      BIDIRECTIONAL='TRUE';
      INPUT_LOAD='(-0.01,0.01)';
      OUTPUT_LOAD='(1.0,-1.0)';
      PINUSE='BI';
    'D':
      PIN_NUMBER='(3)';
      OUTPUT_TYPE='(TS,TS)';
      BIDIRECTIONAL='TRUE';
      INPUT_LOAD='(-0.01,0.01)';
      OUTPUT_LOAD='(1.0,-1.0)';
      PINUSE='BI';
  end_pin;
  body
      PART_NAME='POWERMOS_3P_NCH_V1';
      BODY_NAME='POWERMOS_3P_NCH_V1';
      PHYS_DES_PREFIX='Q';
      CLASS='DISCRETE';
      JEDEC_TYPE='SOT23_V1_H044';
      ALT_SYMBOLS='(SOT23_V1_H044)';
      DESCRIPTION='FET,N-CH,50V,3.5OHM,200MA,SOT23';
      CPN_STATUS='';
      PARENT_PART_TYPE='POWERMOS_3P_NCH_V1';
      PARENT_PPT='POWERMOS_3P_NCH_V1';
      PARENT_PPT_PART='POWERMOS_3P_NCH_V1-G121-10200-01';
  end_body;
end_primitive;
primitive 'POWERMOS_3P_PCH-G121-10216-01';
  pin
    'G':
      PIN_NUMBER='(1)';
      OUTPUT_TYPE='(TS,TS)';
      BIDIRECTIONAL='TRUE';
      INPUT_LOAD='(-0.01,0.01)';
      OUTPUT_LOAD='(1.0,-1.0)';
      PINUSE='BI';
    'S':
      PIN_NUMBER='(2)';
      OUTPUT_TYPE='(TS,TS)';
      BIDIRECTIONAL='TRUE';
      INPUT_LOAD='(-0.01,0.01)';
      OUTPUT_LOAD='(1.0,-1.0)';
      PINUSE='BI';
    'D':
      PIN_NUMBER='(3)';
      OUTPUT_TYPE='(TS,TS)';
      BIDIRECTIONAL='TRUE';
      INPUT_LOAD='(-0.01,0.01)';
      OUTPUT_LOAD='(1.0,-1.0)';
      PINUSE='BI';
  end_pin;
  body
      PART_NAME='POWERMOS_3P_PCH';
      BODY_NAME='POWERMOS_3P_PCH';
      PHYS_DES_PREFIX='Q';
      CLASS='DISCRETE';
      JEDEC_TYPE='SOT23_V1_H045';
      ALT_SYMBOLS='(SOT23_V1_H045)';
      DESCRIPTION='FET,P-CH,30V,65MOHM,3.8A,SOT23';
      CPN_STATUS='';
      PARENT_PART_TYPE='POWERMOS_3P_PCH';
      PARENT_PPT='POWERMOS_3P_PCH';
      PARENT_PPT_PART='POWERMOS_3P_PCH-G121-10216-01';
  end_body;
end_primitive;
primitive 'RESISTOR-A155-05101-DL,5.1KOHMA';
  pin
    '2':
      PIN_NUMBER='(2)';
      PINUSE='UNSPEC';
    '1':
      PIN_NUMBER='(1)';
      PINUSE='UNSPEC';
  end_pin;
  body
      PART_NAME='RESISTOR';
      BODY_NAME='RESISTOR';
      PHYS_DES_PREFIX='R';
      CLASS='DISCRETE';
      JEDEC_TYPE='SMC_0402R_H016';
      ALT_SYMBOLS='(SMC_0402R_C_H016)';
      DESCRIPTION='RES,5.1KOHM,1%,1/16W,0402';
      CPN_STATUS='';
      PARENT_PART_TYPE='RESISTOR';
      PARENT_PPT='RESISTOR';
      PARENT_PPT_PART='RESISTOR-A155-05101-DL,5.1KOHM,1%';
  end_body;
end_primitive;
primitive 'RESISTOR-G152-00055-01,1.13KOHA';
  pin
    '2':
      PIN_NUMBER='(2)';
      PINUSE='UNSPEC';
    '1':
      PIN_NUMBER='(1)';
      PINUSE='UNSPEC';
  end_pin;
  body
      PART_NAME='RESISTOR';
      BODY_NAME='RESISTOR';
      PHYS_DES_PREFIX='R';
      CLASS='DISCRETE';
      JEDEC_TYPE='SMC_0402R';
      ALT_SYMBOLS='(SMC_0402R_C)';
      DESCRIPTION='RESISTOR, SINGLE,1.13KOHM,THICK FILM,1%,50V,.063W,-55/125C,04~
02';
      CPN_STATUS='';
      PARENT_PART_TYPE='RESISTOR';
      PARENT_PPT='RESISTOR';
      PARENT_PPT_PART='RESISTOR-G152-00055-01,1.13KOHM,1%';
  end_body;
end_primitive;
primitive 'RESISTOR-G152-10344-01,30KOHM,A';
  pin
    '2':
      PIN_NUMBER='(2)';
      PINUSE='UNSPEC';
    '1':
      PIN_NUMBER='(1)';
      PINUSE='UNSPEC';
  end_pin;
  body
      PART_NAME='RESISTOR';
      BODY_NAME='RESISTOR';
      PHYS_DES_PREFIX='R';
      CLASS='DISCRETE';
      JEDEC_TYPE='SMC_0402R_H016';
      ALT_SYMBOLS='(SMC_0402R_C_H016)';
      DESCRIPTION='RES,30KOHM,0.1%,0.063W,0402';
      CPN_STATUS='';
      PARENT_PART_TYPE='RESISTOR';
      PARENT_PPT='RESISTOR';
      PARENT_PPT_PART='RESISTOR-G152-10344-01,30KOHM,0.1%';
  end_body;
end_primitive;
primitive 'RESISTOR-G155-01202-01,12KOHM,A';
  pin
    '2':
      PIN_NUMBER='(2)';
      PINUSE='UNSPEC';
    '1':
      PIN_NUMBER='(1)';
      PINUSE='UNSPEC';
  end_pin;
  body
      PART_NAME='RESISTOR';
      BODY_NAME='RESISTOR';
      PHYS_DES_PREFIX='R';
      CLASS='DISCRETE';
      JEDEC_TYPE='SMC_0402R';
      ALT_SYMBOLS='(SMC_0402R_C)';
      DESCRIPTION='RES,12K,1%,0.063W,0402';
      CPN_STATUS='';
      PARENT_PART_TYPE='RESISTOR';
      PARENT_PPT='RESISTOR';
      PARENT_PPT_PART='RESISTOR-G155-01202-01,12KOHM,1%';
  end_body;
end_primitive;
primitive 'RESISTOR-G155-01203-01,120KOHMA';
  pin
    '2':
      PIN_NUMBER='(2)';
      PINUSE='UNSPEC';
    '1':
      PIN_NUMBER='(1)';
      PINUSE='UNSPEC';
  end_pin;
  body
      PART_NAME='RESISTOR';
      BODY_NAME='RESISTOR';
      PHYS_DES_PREFIX='R';
      CLASS='DISCRETE';
      JEDEC_TYPE='SMC_0402R_H016';
      ALT_SYMBOLS='(SMC_0402R_C_H016)';
      DESCRIPTION='RES,120K,1%,0.063W,0402';
      CPN_STATUS='';
      PARENT_PART_TYPE='RESISTOR';
      PARENT_PPT='RESISTOR';
      PARENT_PPT_PART='RESISTOR-G155-01203-01,120KOHM,1%';
  end_body;
end_primitive;
primitive 'RESISTOR-G155-02101-01,2.1KOHMA';
  pin
    '2':
      PIN_NUMBER='(2)';
      PINUSE='UNSPEC';
    '1':
      PIN_NUMBER='(1)';
      PINUSE='UNSPEC';
  end_pin;
  body
      PART_NAME='RESISTOR';
      BODY_NAME='RESISTOR';
      PHYS_DES_PREFIX='R';
      CLASS='DISCRETE';
      JEDEC_TYPE='SMC_0402R';
      ALT_SYMBOLS='(SMC_0402R_C)';
      DESCRIPTION='RES,2.1K,1%,0.063W,0402';
      CPN_STATUS='';
      PARENT_PART_TYPE='RESISTOR';
      PARENT_PPT='RESISTOR';
      PARENT_PPT_PART='RESISTOR-G155-02101-01,2.1KOHM,1%';
  end_body;
end_primitive;
primitive 'RESISTOR-G155-02262-01,22.6K,1%';
  pin
    '2':
      PIN_NUMBER='(2)';
      PINUSE='UNSPEC';
    '1':
      PIN_NUMBER='(1)';
      PINUSE='UNSPEC';
  end_pin;
  body
      PART_NAME='RESISTOR';
      BODY_NAME='RESISTOR';
      PHYS_DES_PREFIX='R';
      CLASS='DISCRETE';
      JEDEC_TYPE='SMC_0402R_H016';
      ALT_SYMBOLS='(SMC_0402R_C_H016)';
      DESCRIPTION='RES,22.6K,1%,0.063W,0402';
      CPN_STATUS='';
      PARENT_PART_TYPE='RESISTOR';
      PARENT_PPT='RESISTOR';
      PARENT_PPT_PART='RESISTOR-G155-02262-01,22.6K,1%';
  end_body;
end_primitive;
primitive 'RESISTOR-G155-02402-01,24KOHM,A';
  pin
    '2':
      PIN_NUMBER='(2)';
      PINUSE='UNSPEC';
    '1':
      PIN_NUMBER='(1)';
      PINUSE='UNSPEC';
  end_pin;
  body
      PART_NAME='RESISTOR';
      BODY_NAME='RESISTOR';
      PHYS_DES_PREFIX='R';
      CLASS='DISCRETE';
      JEDEC_TYPE='SMC_0402R_H016';
      ALT_SYMBOLS='(SMC_0402R_C_H016)';
      DESCRIPTION='RES,24K,1%,0.0625W,0402';
      CPN_STATUS='';
      PARENT_PART_TYPE='RESISTOR';
      PARENT_PPT='RESISTOR';
      PARENT_PPT_PART='RESISTOR-G155-02402-01,24KOHM,1%';
  end_body;
end_primitive;
primitive 'RESISTOR-G155-02672-01,26.7K,1%';
  pin
    '2':
      PIN_NUMBER='(2)';
      PINUSE='UNSPEC';
    '1':
      PIN_NUMBER='(1)';
      PINUSE='UNSPEC';
  end_pin;
  body
      PART_NAME='RESISTOR';
      BODY_NAME='RESISTOR';
      PHYS_DES_PREFIX='R';
      CLASS='DISCRETE';
      JEDEC_TYPE='SMC_0402R_H016';
      ALT_SYMBOLS='(SMC_0402R_C_H016)';
      DESCRIPTION='RES,26.7K,1%,0.063W,0402';
      CPN_STATUS='';
      PARENT_PART_TYPE='RESISTOR';
      PARENT_PPT='RESISTOR';
      PARENT_PPT_PART='RESISTOR-G155-02672-01,26.7K,1%';
  end_body;
end_primitive;
primitive 'RESISTOR-G155-03001-01,3KOHM,1%';
  pin
    '2':
      PIN_NUMBER='(2)';
      PINUSE='UNSPEC';
    '1':
      PIN_NUMBER='(1)';
      PINUSE='UNSPEC';
  end_pin;
  body
      PART_NAME='RESISTOR';
      BODY_NAME='RESISTOR';
      PHYS_DES_PREFIX='R';
      CLASS='DISCRETE';
      JEDEC_TYPE='SMC_0402R_H016';
      ALT_SYMBOLS='(SMC_0402R_C_H016)';
      DESCRIPTION='RES,3K,1%,0.0625W,0402';
      CPN_STATUS='';
      PARENT_PART_TYPE='RESISTOR';
      PARENT_PPT='RESISTOR';
      PARENT_PPT_PART='RESISTOR-G155-03001-01,3KOHM,1%';
  end_body;
end_primitive;
primitive 'RESISTOR-G155-03241-01,3.24KOHA';
  pin
    '2':
      PIN_NUMBER='(2)';
      PINUSE='UNSPEC';
    '1':
      PIN_NUMBER='(1)';
      PINUSE='UNSPEC';
  end_pin;
  body
      PART_NAME='RESISTOR';
      BODY_NAME='RESISTOR';
      PHYS_DES_PREFIX='R';
      CLASS='DISCRETE';
      JEDEC_TYPE='SMC_0402R_H014';
      ALT_SYMBOLS='(SMC_0402R_C_H014)';
      DESCRIPTION='RES,3.24K,1%,0.063W,0402';
      CPN_STATUS='';
      PARENT_PART_TYPE='RESISTOR';
      PARENT_PPT='RESISTOR';
      PARENT_PPT_PART='RESISTOR-G155-03241-01,3.24KOHM,1%';
  end_body;
end_primitive;
primitive 'RESISTOR-G155-03322-01,33.2KOHA';
  pin
    '2':
      PIN_NUMBER='(2)';
      PINUSE='UNSPEC';
    '1':
      PIN_NUMBER='(1)';
      PINUSE='UNSPEC';
  end_pin;
  body
      PART_NAME='RESISTOR';
      BODY_NAME='RESISTOR';
      PHYS_DES_PREFIX='R';
      CLASS='DISCRETE';
      JEDEC_TYPE='SMC_0402R_H016';
      ALT_SYMBOLS='(SMC_0402R_C_H016)';
      DESCRIPTION='RES,33.2K,1%,0.063W,0402';
      CPN_STATUS='';
      PARENT_PART_TYPE='RESISTOR';
      PARENT_PPT='RESISTOR';
      PARENT_PPT_PART='RESISTOR-G155-03322-01,33.2KOHM,1%';
  end_body;
end_primitive;
primitive 'RESISTOR-G155-03921-01,3.92KOHA';
  pin
    '2':
      PIN_NUMBER='(2)';
      PINUSE='UNSPEC';
    '1':
      PIN_NUMBER='(1)';
      PINUSE='UNSPEC';
  end_pin;
  body
      PART_NAME='RESISTOR';
      BODY_NAME='RESISTOR';
      PHYS_DES_PREFIX='R';
      CLASS='DISCRETE';
      JEDEC_TYPE='SMC_0402R';
      ALT_SYMBOLS='(SMC_0402R_C)';
      DESCRIPTION='RES,3.92K,1%,0.063W,0402';
      CPN_STATUS='';
      PARENT_PART_TYPE='RESISTOR';
      PARENT_PPT='RESISTOR';
      PARENT_PPT_PART='RESISTOR-G155-03921-01,3.92KOHM,1%';
  end_body;
end_primitive;
primitive 'RESISTOR-G155-04221-01,4.22KOHA';
  pin
    '2':
      PIN_NUMBER='(2)';
      PINUSE='UNSPEC';
    '1':
      PIN_NUMBER='(1)';
      PINUSE='UNSPEC';
  end_pin;
  body
      PART_NAME='RESISTOR';
      BODY_NAME='RESISTOR';
      PHYS_DES_PREFIX='R';
      CLASS='DISCRETE';
      JEDEC_TYPE='SMC_0402R';
      ALT_SYMBOLS='(SMC_0402R_C)';
      DESCRIPTION='RES,4.22K,1%,0.063W,0402';
      CPN_STATUS='';
      PARENT_PART_TYPE='RESISTOR';
      PARENT_PPT='RESISTOR';
      PARENT_PPT_PART='RESISTOR-G155-04221-01,4.22KOHM,1%';
  end_body;
end_primitive;
primitive 'RESISTOR-G155-04421-01,4.42KOHA';
  pin
    '2':
      PIN_NUMBER='(2)';
      PINUSE='UNSPEC';
    '1':
      PIN_NUMBER='(1)';
      PINUSE='UNSPEC';
  end_pin;
  body
      PART_NAME='RESISTOR';
      BODY_NAME='RESISTOR';
      PHYS_DES_PREFIX='R';
      CLASS='DISCRETE';
      JEDEC_TYPE='SMC_0402R_H016';
      ALT_SYMBOLS='(SMC_0402R_C_H016)';
      DESCRIPTION='RES,4.42K,1%,0.063W,0402';
      CPN_STATUS='';
      PARENT_PART_TYPE='RESISTOR';
      PARENT_PPT='RESISTOR';
      PARENT_PPT_PART='RESISTOR-G155-04421-01,4.42KOHM,1%';
  end_body;
end_primitive;
primitive 'RESISTOR-G155-05101-01,5.1KOHMA';
  pin
    '2':
      PIN_NUMBER='(2)';
      PINUSE='UNSPEC';
    '1':
      PIN_NUMBER='(1)';
      PINUSE='UNSPEC';
  end_pin;
  body
      PART_NAME='RESISTOR';
      BODY_NAME='RESISTOR';
      PHYS_DES_PREFIX='R';
      CLASS='DISCRETE';
      JEDEC_TYPE='SMC_0402R_H016';
      ALT_SYMBOLS='(SMC_0402R_C_H016)';
      DESCRIPTION='RES,5.1K,1%,0.063W,0402';
      CPN_STATUS='';
      PARENT_PART_TYPE='RESISTOR';
      PARENT_PPT='RESISTOR';
      PARENT_PPT_PART='RESISTOR-G155-05101-01,5.1KOHM,1%';
  end_body;
end_primitive;
primitive 'RESISTOR-G155-100R0-J0,0OHM,-';
  pin
    '2':
      PIN_NUMBER='(2)';
      PINUSE='UNSPEC';
    '1':
      PIN_NUMBER='(1)';
      PINUSE='UNSPEC';
  end_pin;
  body
      PART_NAME='RESISTOR';
      BODY_NAME='RESISTOR';
      PHYS_DES_PREFIX='R';
      CLASS='DISCRETE';
      JEDEC_TYPE='SMC_0402R_H016';
      ALT_SYMBOLS='(SMC_0402R_C_H016,C0402-0P8MM-45DG)';
      DESCRIPTION='RES,0,JUMPER,0.0625W,0402';
      CPN_STATUS='PREFER';
      PARENT_PART_TYPE='RESISTOR';
      PARENT_PPT='RESISTOR';
      PARENT_PPT_PART='RESISTOR-G155-100R0-J0,0OHM,-';
  end_body;
end_primitive;
primitive 'RESISTOR-G155-11000-01,100OHM,A';
  pin
    '2':
      PIN_NUMBER='(2)';
      PINUSE='UNSPEC';
    '1':
      PIN_NUMBER='(1)';
      PINUSE='UNSPEC';
  end_pin;
  body
      PART_NAME='RESISTOR';
      BODY_NAME='RESISTOR';
      PHYS_DES_PREFIX='R';
      CLASS='DISCRETE';
      JEDEC_TYPE='SMC_0402R_H016';
      ALT_SYMBOLS='(SMC_0402R_C_H016)';
      DESCRIPTION='RES,100,1%,0.0625W,0402';
      CPN_STATUS='PREFER';
      PARENT_PART_TYPE='RESISTOR';
      PARENT_PPT='RESISTOR';
      PARENT_PPT_PART='RESISTOR-G155-11000-01,100OHM,1%';
  end_body;
end_primitive;
primitive 'RESISTOR-G155-11001-01,1KOHM,1%';
  pin
    '2':
      PIN_NUMBER='(2)';
      PINUSE='UNSPEC';
    '1':
      PIN_NUMBER='(1)';
      PINUSE='UNSPEC';
  end_pin;
  body
      PART_NAME='RESISTOR';
      BODY_NAME='RESISTOR';
      PHYS_DES_PREFIX='R';
      CLASS='DISCRETE';
      JEDEC_TYPE='SMC_0402R_H016';
      ALT_SYMBOLS='(SMC_0402R_C_H016)';
      DESCRIPTION='RES,1K,1%,0.0625W,0402';
      CPN_STATUS='PREFER';
      PARENT_PART_TYPE='RESISTOR';
      PARENT_PPT='RESISTOR';
      PARENT_PPT_PART='RESISTOR-G155-11001-01,1KOHM,1%';
  end_body;
end_primitive;
primitive 'RESISTOR-G155-11002-01,10KOHM,A';
  pin
    '2':
      PIN_NUMBER='(2)';
      PINUSE='UNSPEC';
    '1':
      PIN_NUMBER='(1)';
      PINUSE='UNSPEC';
  end_pin;
  body
      PART_NAME='RESISTOR';
      BODY_NAME='RESISTOR';
      PHYS_DES_PREFIX='R';
      CLASS='DISCRETE';
      JEDEC_TYPE='SMC_0402R_H016';
      ALT_SYMBOLS='(SMC_0402R_C_H016)';
      DESCRIPTION='RES,10K,1%,0.0625W,0402';
      CPN_STATUS='PREFER';
      PARENT_PART_TYPE='RESISTOR';
      PARENT_PPT='RESISTOR';
      PARENT_PPT_PART='RESISTOR-G155-11002-01,10KOHM,1%';
  end_body;
end_primitive;
primitive 'RESISTOR-G155-11003-01,100KOHMA';
  pin
    '2':
      PIN_NUMBER='(2)';
      PINUSE='UNSPEC';
    '1':
      PIN_NUMBER='(1)';
      PINUSE='UNSPEC';
  end_pin;
  body
      PART_NAME='RESISTOR';
      BODY_NAME='RESISTOR';
      PHYS_DES_PREFIX='R';
      CLASS='DISCRETE';
      JEDEC_TYPE='SMC_0402R_H016';
      ALT_SYMBOLS='(SMC_0402R_C_H016)';
      DESCRIPTION='RES,100K,1%,0.0625W,0402';
      CPN_STATUS='PREFER';
      PARENT_PART_TYPE='RESISTOR';
      PARENT_PPT='RESISTOR';
      PARENT_PPT_PART='RESISTOR-G155-11003-01,100KOHM,1%';
  end_body;
end_primitive;
primitive 'RESISTOR-G155-11004-01,1MOHM,1%';
  pin
    '2':
      PIN_NUMBER='(2)';
      PINUSE='UNSPEC';
    '1':
      PIN_NUMBER='(1)';
      PINUSE='UNSPEC';
  end_pin;
  body
      PART_NAME='RESISTOR';
      BODY_NAME='RESISTOR';
      PHYS_DES_PREFIX='R';
      CLASS='DISCRETE';
      JEDEC_TYPE='SMC_0402R_H016';
      ALT_SYMBOLS='(SMC_0402R_C_H016)';
      DESCRIPTION='RES,1M,1%,0.0625W,0402';
      CPN_STATUS='PREFER';
      PARENT_PART_TYPE='RESISTOR';
      PARENT_PPT='RESISTOR';
      PARENT_PPT_PART='RESISTOR-G155-11004-01,1MOHM,1%';
  end_body;
end_primitive;
primitive 'RESISTOR-G155-11500-01,150OHM,A';
  pin
    '2':
      PIN_NUMBER='(2)';
      PINUSE='UNSPEC';
    '1':
      PIN_NUMBER='(1)';
      PINUSE='UNSPEC';
  end_pin;
  body
      PART_NAME='RESISTOR';
      BODY_NAME='RESISTOR';
      PHYS_DES_PREFIX='R';
      CLASS='DISCRETE';
      JEDEC_TYPE='SMC_0402R_H016';
      ALT_SYMBOLS='(SMC_0402R_C_H016)';
      DESCRIPTION='RES,150,1%,0.0625W,0402';
      CPN_STATUS='PREFER';
      PARENT_PART_TYPE='RESISTOR';
      PARENT_PPT='RESISTOR';
      PARENT_PPT_PART='RESISTOR-G155-11500-01,150OHM,1%';
  end_body;
end_primitive;
primitive 'RESISTOR-G155-11502-01,15KOHM,A';
  pin
    '2':
      PIN_NUMBER='(2)';
      PINUSE='UNSPEC';
    '1':
      PIN_NUMBER='(1)';
      PINUSE='UNSPEC';
  end_pin;
  body
      PART_NAME='RESISTOR';
      BODY_NAME='RESISTOR';
      PHYS_DES_PREFIX='R';
      CLASS='DISCRETE';
      JEDEC_TYPE='SMC_0402R_H016';
      ALT_SYMBOLS='(SMC_0402R_C_H016)';
      DESCRIPTION='RES,15K,1%,0.0625W,0402';
      CPN_STATUS='PREFER';
      PARENT_PART_TYPE='RESISTOR';
      PARENT_PPT='RESISTOR';
      PARENT_PPT_PART='RESISTOR-G155-11502-01,15KOHM,1%';
  end_body;
end_primitive;
primitive 'RESISTOR-G155-12002-01,20KOHM,A';
  pin
    '2':
      PIN_NUMBER='(2)';
      PINUSE='UNSPEC';
    '1':
      PIN_NUMBER='(1)';
      PINUSE='UNSPEC';
  end_pin;
  body
      PART_NAME='RESISTOR';
      BODY_NAME='RESISTOR';
      PHYS_DES_PREFIX='R';
      CLASS='DISCRETE';
      JEDEC_TYPE='SMC_0402R_H016';
      ALT_SYMBOLS='(SMC_0402R_C_H016)';
      DESCRIPTION='RES,20K,1%,0.0625W,0402';
      CPN_STATUS='PREFER';
      PARENT_PART_TYPE='RESISTOR';
      PARENT_PPT='RESISTOR';
      PARENT_PPT_PART='RESISTOR-G155-12002-01,20KOHM,1%';
  end_body;
end_primitive;
primitive 'RESISTOR-G155-120R0-01,20OHM,1%';
  pin
    '2':
      PIN_NUMBER='(2)';
      PINUSE='UNSPEC';
    '1':
      PIN_NUMBER='(1)';
      PINUSE='UNSPEC';
  end_pin;
  body
      PART_NAME='RESISTOR';
      BODY_NAME='RESISTOR';
      PHYS_DES_PREFIX='R';
      CLASS='DISCRETE';
      JEDEC_TYPE='SMC_0402R_H016';
      ALT_SYMBOLS='(SMC_0402R_C_H016)';
      DESCRIPTION='RES,20,1%,0.0625W,0402';
      CPN_STATUS='PREFER';
      PARENT_PART_TYPE='RESISTOR';
      PARENT_PPT='RESISTOR';
      PARENT_PPT_PART='RESISTOR-G155-120R0-01,20OHM,1%';
  end_body;
end_primitive;
primitive 'RESISTOR-G155-12201-01,2.2KOHMA';
  pin
    '2':
      PIN_NUMBER='(2)';
      PINUSE='UNSPEC';
    '1':
      PIN_NUMBER='(1)';
      PINUSE='UNSPEC';
  end_pin;
  body
      PART_NAME='RESISTOR';
      BODY_NAME='RESISTOR';
      PHYS_DES_PREFIX='R';
      CLASS='DISCRETE';
      JEDEC_TYPE='SMC_0402R_H016';
      ALT_SYMBOLS='(SMC_0402R_C_H016)';
      DESCRIPTION='RES,2.2K,1%0.0625W,0402';
      CPN_STATUS='PREFER';
      PARENT_PART_TYPE='RESISTOR';
      PARENT_PPT='RESISTOR';
      PARENT_PPT_PART='RESISTOR-G155-12201-01,2.2KOHM,1%';
  end_body;
end_primitive;
primitive 'RESISTOR-G155-13300-01,330OHM,A';
  pin
    '2':
      PIN_NUMBER='(2)';
      PINUSE='UNSPEC';
    '1':
      PIN_NUMBER='(1)';
      PINUSE='UNSPEC';
  end_pin;
  body
      PART_NAME='RESISTOR';
      BODY_NAME='RESISTOR';
      PHYS_DES_PREFIX='R';
      CLASS='DISCRETE';
      JEDEC_TYPE='SMC_0402R_H016';
      ALT_SYMBOLS='(SMC_0402R_C_H016)';
      DESCRIPTION='RES,330,1%,0.0625W,0402';
      CPN_STATUS='PREFER';
      PARENT_PART_TYPE='RESISTOR';
      PARENT_PPT='RESISTOR';
      PARENT_PPT_PART='RESISTOR-G155-13300-01,330OHM,1%';
  end_body;
end_primitive;
primitive 'RESISTOR-G155-133R0-01,33OHM,1%';
  pin
    '2':
      PIN_NUMBER='(2)';
      PINUSE='UNSPEC';
    '1':
      PIN_NUMBER='(1)';
      PINUSE='UNSPEC';
  end_pin;
  body
      PART_NAME='RESISTOR';
      BODY_NAME='RESISTOR';
      PHYS_DES_PREFIX='R';
      CLASS='DISCRETE';
      JEDEC_TYPE='SMC_0402R_H016';
      ALT_SYMBOLS='(SMC_0402R_C_H016)';
      DESCRIPTION='RES,33,1%,0.0625W,0402';
      CPN_STATUS='PREFER';
      PARENT_PART_TYPE='RESISTOR';
      PARENT_PPT='RESISTOR';
      PARENT_PPT_PART='RESISTOR-G155-133R0-01,33OHM,1%';
  end_body;
end_primitive;
primitive 'RESISTOR-G155-14701-01,4.7KOHMA';
  pin
    '2':
      PIN_NUMBER='(2)';
      PINUSE='UNSPEC';
    '1':
      PIN_NUMBER='(1)';
      PINUSE='UNSPEC';
  end_pin;
  body
      PART_NAME='RESISTOR';
      BODY_NAME='RESISTOR';
      PHYS_DES_PREFIX='R';
      CLASS='DISCRETE';
      JEDEC_TYPE='SMC_0402R_H016';
      ALT_SYMBOLS='(SMC_0402R_C_H016)';
      DESCRIPTION='RES,4.7K,1%,0.0625W,0402';
      CPN_STATUS='PREFER';
      PARENT_PART_TYPE='RESISTOR';
      PARENT_PPT='RESISTOR';
      PARENT_PPT_PART='RESISTOR-G155-14701-01,4.7KOHM,1%';
  end_body;
end_primitive;
primitive 'RESISTOR-G155-149R9-01,49.9OHMA';
  pin
    '2':
      PIN_NUMBER='(2)';
      PINUSE='UNSPEC';
    '1':
      PIN_NUMBER='(1)';
      PINUSE='UNSPEC';
  end_pin;
  body
      PART_NAME='RESISTOR';
      BODY_NAME='RESISTOR';
      PHYS_DES_PREFIX='R';
      CLASS='DISCRETE';
      JEDEC_TYPE='SMC_0402R_H016';
      ALT_SYMBOLS='(SMC_0402R_C_H016)';
      DESCRIPTION='RES,49.9,1%,0.0625W,0402';
      CPN_STATUS='PREFER';
      PARENT_PART_TYPE='RESISTOR';
      PARENT_PPT='RESISTOR';
      PARENT_PPT_PART='RESISTOR-G155-149R9-01,49.9OHM,1%';
  end_body;
end_primitive;
primitive 'RESISTOR-G156-049R9-01,49.9OHMA';
  pin
    '2':
      PIN_NUMBER='(2)';
      PINUSE='UNSPEC';
    '1':
      PIN_NUMBER='(1)';
      PINUSE='UNSPEC';
  end_pin;
  body
      PART_NAME='RESISTOR';
      BODY_NAME='RESISTOR';
      PHYS_DES_PREFIX='R';
      CLASS='DISCRETE';
      JEDEC_TYPE='SMC_0603R_H022';
      ALT_SYMBOLS='(SMC_0603R_H022)';
      DESCRIPTION='RES,49.9,1%,0.1W,0603';
      CPN_STATUS='';
      PARENT_PART_TYPE='RESISTOR';
      PARENT_PPT='RESISTOR';
      PARENT_PPT_PART='RESISTOR-G156-049R9-01,49.9OHM,1%';
  end_body;
end_primitive;
primitive 'RESISTOR-G156-100R0-J0,0OHM,-';
  pin
    '2':
      PIN_NUMBER='(2)';
      PINUSE='UNSPEC';
    '1':
      PIN_NUMBER='(1)';
      PINUSE='UNSPEC';
  end_pin;
  body
      PART_NAME='RESISTOR';
      BODY_NAME='RESISTOR';
      PHYS_DES_PREFIX='R';
      CLASS='DISCRETE';
      JEDEC_TYPE='SMC_0603R_H024';
      ALT_SYMBOLS='(SMC_0603R_H024)';
      DESCRIPTION='RES,0,JUMPER,0.1W,0603';
      CPN_STATUS='PREFER';
      PARENT_PART_TYPE='RESISTOR';
      PARENT_PPT='RESISTOR';
      PARENT_PPT_PART='RESISTOR-G156-100R0-J0,0OHM,-';
  end_body;
end_primitive;
primitive 'RESISTOR-G157-100R0-J0,0OHM,-';
  pin
    '2':
      PIN_NUMBER='(2)';
      PINUSE='UNSPEC';
    '1':
      PIN_NUMBER='(1)';
      PINUSE='UNSPEC';
  end_pin;
  body
      PART_NAME='RESISTOR';
      BODY_NAME='RESISTOR';
      PHYS_DES_PREFIX='R';
      CLASS='DISCRETE';
      JEDEC_TYPE='SMC_0805R_H026';
      ALT_SYMBOLS='(SMC_0805R_H026)';
      DESCRIPTION='RES,0,JUMPER,0.125W,0805';
      CPN_STATUS='PREFER';
      PARENT_PART_TYPE='RESISTOR';
      PARENT_PPT='RESISTOR';
      PARENT_PPT_PART='RESISTOR-G157-100R0-J0,0OHM,-';
  end_body;
end_primitive;
primitive 'RESISTOR-G157-12R20-01,2.2OHM,A';
  pin
    '2':
      PIN_NUMBER='(2)';
      PINUSE='UNSPEC';
    '1':
      PIN_NUMBER='(1)';
      PINUSE='UNSPEC';
  end_pin;
  body
      PART_NAME='RESISTOR';
      BODY_NAME='RESISTOR';
      PHYS_DES_PREFIX='R';
      CLASS='DISCRETE';
      JEDEC_TYPE='SMC_0805R_H026';
      ALT_SYMBOLS='(SMC_0805R_H026)';
      DESCRIPTION='RES,2.2,1%,0.125W,0805';
      CPN_STATUS='PREFER';
      PARENT_PART_TYPE='RESISTOR';
      PARENT_PPT='RESISTOR';
      PARENT_PPT_PART='RESISTOR-G157-12R20-01,2.2OHM,1%';
  end_body;
end_primitive;
primitive 'SHT31A_DIS_B10KS_DFN8-A222-000A';
  pin
    'SDA':
      PIN_NUMBER='(1)';
      OUTPUT_TYPE='(TS,TS)';
      BIDIRECTIONAL='TRUE';
      INPUT_LOAD='(-0.01,0.01)';
      OUTPUT_LOAD='(1.0,-1.0)';
      PINUSE='BI';
    'ADDR':
      PIN_NUMBER='(2)';
      INPUT_LOAD='(-0.01,0.01)';
      PINUSE='IN';
    'ALERT':
      PIN_NUMBER='(3)';
      OUTPUT_LOAD='(1.0,-1.0)';
      PINUSE='OUT';
    'SCL':
      PIN_NUMBER='(4)';
      OUTPUT_TYPE='(TS,TS)';
      BIDIRECTIONAL='TRUE';
      INPUT_LOAD='(-0.01,0.01)';
      OUTPUT_LOAD='(1.0,-1.0)';
      PINUSE='BI';
    'VDD':
      PIN_NUMBER='(5)';
      PINUSE='POWER';
      NO_LOAD_CHECK='Both';
      NO_IO_CHECK='Both';
      NO_ASSERT_CHECK='TRUE';
      NO_DIR_CHECK='TRUE';
      ALLOW_CONNECT='TRUE';
    'RESET*':
      PIN_NUMBER='(6)';
      INPUT_LOAD='(-0.01,0.01)';
      PINUSE='IN';
    'R':
      PIN_NUMBER='(7)';
      OUTPUT_TYPE='(TS,TS)';
      BIDIRECTIONAL='TRUE';
      INPUT_LOAD='(-0.01,0.01)';
      OUTPUT_LOAD='(1.0,-1.0)';
      PINUSE='BI';
    'VSS':
      PIN_NUMBER='(8)';
      PINUSE='GROUND';
      NO_LOAD_CHECK='Both';
      NO_IO_CHECK='Both';
      NO_ASSERT_CHECK='TRUE';
      NO_DIR_CHECK='TRUE';
      ALLOW_CONNECT='TRUE';
    'THRM_PAD':
      PIN_NUMBER='(9)';
      PINUSE='GROUND';
      NO_LOAD_CHECK='Both';
      NO_IO_CHECK='Both';
      NO_ASSERT_CHECK='TRUE';
      NO_DIR_CHECK='TRUE';
      ALLOW_CONNECT='TRUE';
  end_pin;
  body
      PART_NAME='SHT31A_DIS_B10KS_DFN8';
      BODY_NAME='SHT31A_DIS_B10KS_DFN8';
      PHYS_DES_PREFIX='U';
      CLASS='IC';
      JEDEC_TYPE='DFN9_098_P0197_TR039X071';
      ALT_SYMBOLS='(DFN9_098_P0197_TR039X071)';
      DESCRIPTION='IC,SHT31A-DIS,HUMIDITY AND TEMPERATURE SENSOR,SMT,DFN-8';
      CPN_STATUS='';
      PARENT_PART_TYPE='SHT31A_DIS_B10KS_DFN8';
      PARENT_PPT='SHT31A_DIS_B10KS_DFN8';
      PARENT_PPT_PART='SHT31A_DIS_B10KS_DFN8-A222-00001-FB,SHT31A-DIS-B10KS';
  end_body;
end_primitive;
primitive 'SOLDER_PREFORM-G380-10015-01';
  pin
    '1':
      PIN_NUMBER='(1)';
      OUTPUT_TYPE='(TS,TS)';
      BIDIRECTIONAL='TRUE';
      INPUT_LOAD='(-0.01,0.01)';
      OUTPUT_LOAD='(1.0,-1.0)';
      PINUSE='BI';
    '2':
      PIN_NUMBER='(2)';
      OUTPUT_TYPE='(TS,TS)';
      BIDIRECTIONAL='TRUE';
      INPUT_LOAD='(-0.01,0.01)';
      OUTPUT_LOAD='(1.0,-1.0)';
      PINUSE='BI';
  end_pin;
  body
      PART_NAME='SOLDER_PREFORM';
      BODY_NAME='SOLDER_PREFORM';
      PHYS_DES_PREFIX='SP';
      CLASS='IO';
      JEDEC_TYPE='0201_SOLDER_PREFORM_4MIL';
      ALT_SYMBOLS='(0201_SOLDER_PREFORM_5MIL)';
      DESCRIPTION='SOLDER PREFORM,ALLOY SAC305,0201';
      PARENT_PART_TYPE='SOLDER_PREFORM';
      PARENT_PPT='SOLDER_PREFORM';
      PARENT_PPT_PART='SOLDER_PREFORM-G380-10015-01';
  end_body;
end_primitive;
primitive 'TPS2051BDBVT_SOT23_5-G220-1033A';
  pin
    'OUT':
      PIN_NUMBER='(1,0)';
      OUTPUT_LOAD='(1.0,-1.0)';
      PINUSE='OUT';
    'OC*':
      PIN_NUMBER='(3,0)';
      OUTPUT_LOAD='(1.0,-1.0)';
      PINUSE='OUT';
    'IN':
      PIN_NUMBER='(5,0)';
      INPUT_LOAD='(-0.01,0.01)';
      PINUSE='IN';
    'EN':
      PIN_NUMBER='(4,0)';
      INPUT_LOAD='(-0.01,0.01)';
      PINUSE='IN';
    'GND':
      PIN_NUMBER='(0,2)';
      PINUSE='GROUND';
      NO_LOAD_CHECK='Both';
      NO_IO_CHECK='Both';
      NO_ASSERT_CHECK='TRUE';
      NO_DIR_CHECK='TRUE';
      ALLOW_CONNECT='TRUE';
  end_pin;
  body
      PART_NAME='TPS2051BDBVT_SOT23_5';
      BODY_NAME='TPS2051BDBVT_SOT23_5';
      PHYS_DES_PREFIX='U';
      CLASS='IC';
      JEDEC_TYPE='SOT23_5';
      ALT_SYMBOLS='(SOT23_5)';
      DESCRIPTION='IC,POWER SWITCH,CURRENT-LIMITED,0.5A,SOT-23';
      PARENT_PART_TYPE='TPS2051BDBVT_SOT23_5';
      PARENT_PPT='TPS2051BDBVT_SOT23_5';
      PARENT_PPT_PART='TPS2051BDBVT_SOT23_5-G220-10338-01';
  end_body;
end_primitive;
primitive 'TPS3808G18DBVR_SOT23_6-G222-00A';
  pin
    'RESET*':
      PIN_NUMBER='(1)';
      OUTPUT_LOAD='(1.0,-1.0)';
      PINUSE='OUT';
    'GND':
      PIN_NUMBER='(2)';
      PINUSE='GROUND';
      NO_LOAD_CHECK='Both';
      NO_IO_CHECK='Both';
      NO_ASSERT_CHECK='TRUE';
      NO_DIR_CHECK='TRUE';
      ALLOW_CONNECT='TRUE';
    'MR*':
      PIN_NUMBER='(3)';
      OUTPUT_TYPE='(TS,TS)';
      BIDIRECTIONAL='TRUE';
      INPUT_LOAD='(-0.01,0.01)';
      OUTPUT_LOAD='(1.0,-1.0)';
      PINUSE='BI';
    'CT':
      PIN_NUMBER='(4)';
      OUTPUT_TYPE='(TS,TS)';
      BIDIRECTIONAL='TRUE';
      INPUT_LOAD='(-0.01,0.01)';
      OUTPUT_LOAD='(1.0,-1.0)';
      PINUSE='BI';
    'SENSE':
      PIN_NUMBER='(5)';
      OUTPUT_TYPE='(TS,TS)';
      BIDIRECTIONAL='TRUE';
      INPUT_LOAD='(-0.01,0.01)';
      OUTPUT_LOAD='(1.0,-1.0)';
      PINUSE='BI';
    'VDD':
      PIN_NUMBER='(6)';
      PINUSE='POWER';
      NO_LOAD_CHECK='Both';
      NO_IO_CHECK='Both';
      NO_ASSERT_CHECK='TRUE';
      NO_DIR_CHECK='TRUE';
      ALLOW_CONNECT='TRUE';
  end_pin;
  body
      PART_NAME='TPS3808G18DBVR_SOT23_6';
      BODY_NAME='TPS3808G18DBVR_SOT23_6';
      PHYS_DES_PREFIX='U';
      CLASS='IC';
      JEDEC_TYPE='SOT23_6';
      ALT_SYMBOLS='(SOT23_6)';
      DESCRIPTION='IC,TPS3808G33,PWR-SUPRVSR,ADJ,SOT23-6';
      PARENT_PART_TYPE='TPS3808G18DBVR_SOT23_6';
      PARENT_PPT='TPS3808G18DBVR_SOT23_6';
      PARENT_PPT_PART='TPS3808G18DBVR_SOT23_6-G222-00082-01';
  end_body;
end_primitive;
primitive 'TPS54824RNVR_VQFN18-G220-10657A';
  pin
    'BOOT':
      PIN_NUMBER='(1)';
      INPUT_LOAD='(-0.01,0.01)';
      PINUSE='IN';
    'VIN_1':
      PIN_NUMBER='(2)';
      INPUT_LOAD='(-0.01,0.01)';
      PINUSE='IN';
    'PGND_1':
      PIN_NUMBER='(3)';
      PINUSE='GROUND';
      NO_LOAD_CHECK='Both';
      NO_IO_CHECK='Both';
      NO_ASSERT_CHECK='TRUE';
      NO_DIR_CHECK='TRUE';
      ALLOW_CONNECT='TRUE';
    'PGND_2':
      PIN_NUMBER='(4)';
      PINUSE='GROUND';
      NO_LOAD_CHECK='Both';
      NO_IO_CHECK='Both';
      NO_ASSERT_CHECK='TRUE';
      NO_DIR_CHECK='TRUE';
      ALLOW_CONNECT='TRUE';
    'PGND_3':
      PIN_NUMBER='(5)';
      PINUSE='GROUND';
      NO_LOAD_CHECK='Both';
      NO_IO_CHECK='Both';
      NO_ASSERT_CHECK='TRUE';
      NO_DIR_CHECK='TRUE';
      ALLOW_CONNECT='TRUE';
    'SW_1':
      PIN_NUMBER='(6)';
      OUTPUT_LOAD='(1.0,-1.0)';
      PINUSE='OUT';
    'SW_2':
      PIN_NUMBER='(7)';
      OUTPUT_LOAD='(1.0,-1.0)';
      PINUSE='OUT';
    'PGND_4':
      PIN_NUMBER='(8)';
      PINUSE='GROUND';
      NO_LOAD_CHECK='Both';
      NO_IO_CHECK='Both';
      NO_ASSERT_CHECK='TRUE';
      NO_DIR_CHECK='TRUE';
      ALLOW_CONNECT='TRUE';
    'PGND_5':
      PIN_NUMBER='(9)';
      PINUSE='GROUND';
      NO_LOAD_CHECK='Both';
      NO_IO_CHECK='Both';
      NO_ASSERT_CHECK='TRUE';
      NO_DIR_CHECK='TRUE';
      ALLOW_CONNECT='TRUE';
    'PGND_6':
      PIN_NUMBER='(10)';
      PINUSE='GROUND';
      NO_LOAD_CHECK='Both';
      NO_IO_CHECK='Both';
      NO_ASSERT_CHECK='TRUE';
      NO_DIR_CHECK='TRUE';
      ALLOW_CONNECT='TRUE';
    'VIN_2':
      PIN_NUMBER='(11)';
      PINUSE='POWER';
      NO_LOAD_CHECK='Both';
      NO_IO_CHECK='Both';
      NO_ASSERT_CHECK='TRUE';
      NO_DIR_CHECK='TRUE';
      ALLOW_CONNECT='TRUE';
    'AGND':
      PIN_NUMBER='(12)';
      PINUSE='GROUND';
      NO_LOAD_CHECK='Both';
      NO_IO_CHECK='Both';
      NO_ASSERT_CHECK='TRUE';
      NO_DIR_CHECK='TRUE';
      ALLOW_CONNECT='TRUE';
    'RT/CLK':
      PIN_NUMBER='(13)';
      INPUT_LOAD='(-0.01,0.01)';
      PINUSE='IN';
    'FB':
      PIN_NUMBER='(14)';
      INPUT_LOAD='(-0.01,0.01)';
      PINUSE='IN';
    'COMP':
      PIN_NUMBER='(15)';
      INPUT_LOAD='(-0.01,0.01)';
      PINUSE='IN';
    'SS/TRK':
      PIN_NUMBER='(16)';
      INPUT_LOAD='(-0.01,0.01)';
      PINUSE='IN';
    'EN':
      PIN_NUMBER='(17)';
      INPUT_LOAD='(-0.01,0.01)';
      PINUSE='IN';
    'PGOOD':
      PIN_NUMBER='(18)';
      OUTPUT_LOAD='(1.0,-1.0)';
      PINUSE='OUT';
  end_pin;
  body
      PART_NAME='TPS54824RNVR_VQFN18';
      BODY_NAME='TPS54824RNVR_VQFN18';
      PHYS_DES_PREFIX='U';
      CLASS='IC';
      JEDEC_TYPE='QFN18_138_P0197_V1';
      ALT_SYMBOLS='(QFN18_138_P0197_V1)';
      DESCRIPTION='IC,TPS54424RNVT,4.5V-17V INPUT 4A DC-DC CONVERTER,QFN 18';
      CPN_STATUS='';
      PARENT_PART_TYPE='TPS54824RNVR_VQFN18';
      PARENT_PPT='TPS54824RNVR_VQFN18';
      PARENT_PPT_PART='TPS54824RNVR_VQFN18-G220-10657-01,TPS54424RNVT';
  end_body;
end_primitive;
primitive 'TP_PIONT-TP010CT020B030_PTH-TPA';
  pin
    '1':
      PIN_NUMBER='(1)';
      PINUSE='UNSPEC';
      NO_LOAD_CHECK='Both';
      NO_IO_CHECK='Both';
      ALLOW_CONNECT='TRUE';
  end_pin;
  body
      PART_NAME='TP_PIONT';
      BODY_NAME='TP_PIONT';
      TEC='TERM';
      UNKNOWN_LOADING='TRUE';
      PHYS_DES_PREFIX='TP';
      CLASS='IO';
      JEDEC_TYPE='TP010CT020B030_PTH';
      PARENT_PART_TYPE='TP_PIONT';
      SCH_MODIFIED_PART='TRUE';
      PARENT_PPT='TP_PIONT';
      PARENT_PPT_PART='TP_PIONT-TP010CT020B030_PTH';
  end_body;
end_primitive;
primitive 'TS3A5018PWR_TSSOP16-G220-10324A';
  pin
    'COM1':
      PIN_NUMBER='(4,0)';
      OUTPUT_TYPE='(TS,TS)';
      BIDIRECTIONAL='TRUE';
      INPUT_LOAD='(-0.01,0.01)';
      OUTPUT_LOAD='(1.0,-1.0)';
      PINUSE='BI';
    'COM2':
      PIN_NUMBER='(7,0)';
      OUTPUT_TYPE='(TS,TS)';
      BIDIRECTIONAL='TRUE';
      INPUT_LOAD='(-0.01,0.01)';
      OUTPUT_LOAD='(1.0,-1.0)';
      PINUSE='BI';
    'COM3':
      PIN_NUMBER='(9,0)';
      OUTPUT_TYPE='(TS,TS)';
      BIDIRECTIONAL='TRUE';
      INPUT_LOAD='(-0.01,0.01)';
      OUTPUT_LOAD='(1.0,-1.0)';
      PINUSE='BI';
    'COM4':
      PIN_NUMBER='(12,0)';
      OUTPUT_TYPE='(TS,TS)';
      BIDIRECTIONAL='TRUE';
      INPUT_LOAD='(-0.01,0.01)';
      OUTPUT_LOAD='(1.0,-1.0)';
      PINUSE='BI';
    'EN*':
      PIN_NUMBER='(15,0)';
      OUTPUT_TYPE='(TS,TS)';
      BIDIRECTIONAL='TRUE';
      INPUT_LOAD='(-0.01,0.01)';
      OUTPUT_LOAD='(1.0,-1.0)';
      PINUSE='BI';
    'IN':
      PIN_NUMBER='(1,0)';
      OUTPUT_TYPE='(TS,TS)';
      BIDIRECTIONAL='TRUE';
      INPUT_LOAD='(-0.01,0.01)';
      OUTPUT_LOAD='(1.0,-1.0)';
      PINUSE='BI';
    'NC1':
      PIN_NUMBER='(2,0)';
      OUTPUT_TYPE='(TS,TS)';
      BIDIRECTIONAL='TRUE';
      INPUT_LOAD='(-0.01,0.01)';
      OUTPUT_LOAD='(1.0,-1.0)';
      PINUSE='BI';
    'NC2':
      PIN_NUMBER='(5,0)';
      OUTPUT_TYPE='(TS,TS)';
      BIDIRECTIONAL='TRUE';
      INPUT_LOAD='(-0.01,0.01)';
      OUTPUT_LOAD='(1.0,-1.0)';
      PINUSE='BI';
    'NC3':
      PIN_NUMBER='(11,0)';
      OUTPUT_TYPE='(TS,TS)';
      BIDIRECTIONAL='TRUE';
      INPUT_LOAD='(-0.01,0.01)';
      OUTPUT_LOAD='(1.0,-1.0)';
      PINUSE='BI';
    'NC4':
      PIN_NUMBER='(14,0)';
      OUTPUT_TYPE='(TS,TS)';
      BIDIRECTIONAL='TRUE';
      INPUT_LOAD='(-0.01,0.01)';
      OUTPUT_LOAD='(1.0,-1.0)';
      PINUSE='BI';
    'NO1':
      PIN_NUMBER='(3,0)';
      OUTPUT_TYPE='(TS,TS)';
      BIDIRECTIONAL='TRUE';
      INPUT_LOAD='(-0.01,0.01)';
      OUTPUT_LOAD='(1.0,-1.0)';
      PINUSE='BI';
    'NO2':
      PIN_NUMBER='(6,0)';
      OUTPUT_TYPE='(TS,TS)';
      BIDIRECTIONAL='TRUE';
      INPUT_LOAD='(-0.01,0.01)';
      OUTPUT_LOAD='(1.0,-1.0)';
      PINUSE='BI';
    'NO3':
      PIN_NUMBER='(10,0)';
      OUTPUT_TYPE='(TS,TS)';
      BIDIRECTIONAL='TRUE';
      INPUT_LOAD='(-0.01,0.01)';
      OUTPUT_LOAD='(1.0,-1.0)';
      PINUSE='BI';
    'NO4':
      PIN_NUMBER='(13,0)';
      OUTPUT_TYPE='(TS,TS)';
      BIDIRECTIONAL='TRUE';
      INPUT_LOAD='(-0.01,0.01)';
      OUTPUT_LOAD='(1.0,-1.0)';
      PINUSE='BI';
    'GND':
      PIN_NUMBER='(0,8)';
      PINUSE='GROUND';
      NO_LOAD_CHECK='Both';
      NO_IO_CHECK='Both';
      NO_ASSERT_CHECK='TRUE';
      NO_DIR_CHECK='TRUE';
      ALLOW_CONNECT='TRUE';
    'V_P':
      PIN_NUMBER='(0,16)';
      PINUSE='POWER';
      NO_LOAD_CHECK='Both';
      NO_IO_CHECK='Both';
      NO_ASSERT_CHECK='TRUE';
      NO_DIR_CHECK='TRUE';
      ALLOW_CONNECT='TRUE';
  end_pin;
  body
      PART_NAME='TS3A5018PWR_TSSOP16';
      BODY_NAME='TS3A5018PWR_TSSOP16';
      PHYS_DES_PREFIX='U';
      CLASS='IC';
      JEDEC_TYPE='SOP16_173_P0256';
      ALT_SYMBOLS='(SOP16_173_P0256)';
      DESCRIPTION='IC,TS3A5018,ANALOG SWITCH,QUAD SPDT,TSSOP16';
      PARENT_PART_TYPE='TS3A5018PWR_TSSOP16';
      PARENT_PPT='TS3A5018PWR_TSSOP16';
      PARENT_PPT_PART='TS3A5018PWR_TSSOP16-G220-10324-01';
  end_body;
end_primitive;
primitive 'TS3USB3031RMGR_WQFN12-G220-103A';
  pin
    'VCC':
      PIN_NUMBER='(12)';
      PINUSE='POWER';
      NO_LOAD_CHECK='Both';
      NO_IO_CHECK='Both';
      NO_ASSERT_CHECK='TRUE';
      NO_DIR_CHECK='TRUE';
      ALLOW_CONNECT='TRUE';
    'D_P':
      PIN_NUMBER='(11)';
      OUTPUT_TYPE='(TS,TS)';
      BIDIRECTIONAL='TRUE';
      INPUT_LOAD='(-0.01,0.01)';
      OUTPUT_LOAD='(1.0,-1.0)';
      PINUSE='BI';
    'D_N':
      PIN_NUMBER='(10)';
      OUTPUT_TYPE='(TS,TS)';
      BIDIRECTIONAL='TRUE';
      INPUT_LOAD='(-0.01,0.01)';
      OUTPUT_LOAD='(1.0,-1.0)';
      PINUSE='BI';
    'SEL0':
      PIN_NUMBER='(1)';
      INPUT_LOAD='(-0.01,0.01)';
      PINUSE='IN';
    'SEL1':
      PIN_NUMBER='(2)';
      INPUT_LOAD='(-0.01,0.01)';
      PINUSE='IN';
    'USB1_P':
      PIN_NUMBER='(3)';
      OUTPUT_TYPE='(TS,TS)';
      BIDIRECTIONAL='TRUE';
      INPUT_LOAD='(-0.01,0.01)';
      OUTPUT_LOAD='(1.0,-1.0)';
      PINUSE='BI';
    'USB1_N':
      PIN_NUMBER='(4)';
      OUTPUT_TYPE='(TS,TS)';
      BIDIRECTIONAL='TRUE';
      INPUT_LOAD='(-0.01,0.01)';
      OUTPUT_LOAD='(1.0,-1.0)';
      PINUSE='BI';
    'USB2_P':
      PIN_NUMBER='(5)';
      OUTPUT_TYPE='(TS,TS)';
      BIDIRECTIONAL='TRUE';
      INPUT_LOAD='(-0.01,0.01)';
      OUTPUT_LOAD='(1.0,-1.0)';
      PINUSE='BI';
    'USB2_N':
      PIN_NUMBER='(6)';
      OUTPUT_TYPE='(TS,TS)';
      BIDIRECTIONAL='TRUE';
      INPUT_LOAD='(-0.01,0.01)';
      OUTPUT_LOAD='(1.0,-1.0)';
      PINUSE='BI';
    'MHL_P':
      PIN_NUMBER='(7)';
      OUTPUT_TYPE='(TS,TS)';
      BIDIRECTIONAL='TRUE';
      INPUT_LOAD='(-0.01,0.01)';
      OUTPUT_LOAD='(1.0,-1.0)';
      PINUSE='BI';
    'MHL_N':
      PIN_NUMBER='(8)';
      OUTPUT_TYPE='(TS,TS)';
      BIDIRECTIONAL='TRUE';
      INPUT_LOAD='(-0.01,0.01)';
      OUTPUT_LOAD='(1.0,-1.0)';
      PINUSE='BI';
    'GND':
      PIN_NUMBER='(9)';
      PINUSE='GROUND';
      NO_LOAD_CHECK='Both';
      NO_IO_CHECK='Both';
      NO_ASSERT_CHECK='TRUE';
      NO_DIR_CHECK='TRUE';
      ALLOW_CONNECT='TRUE';
  end_pin;
  body
      PART_NAME='TS3USB3031RMGR_WQFN12';
      BODY_NAME='TS3USB3031RMGR_WQFN12';
      PHYS_DES_PREFIX='U';
      CLASS='IC';
      JEDEC_TYPE='QFN12_071_P0157';
      ALT_SYMBOLS='(QFN12_071_P0157)';
      DESCRIPTION='IC,DUAL USB 2.0 HS,5.5V,12P,WQFN,SMT';
      PARENT_PART_TYPE='TS3USB3031RMGR_WQFN12';
      PARENT_PPT='TS3USB3031RMGR_WQFN12';
      PARENT_PPT_PART='TS3USB3031RMGR_WQFN12-G220-10368-01,TS3USB3031RMGR';
  end_body;
end_primitive;
primitive 'XC7A200T_2FBG484C_FBG484-G240-A';
  pin
    'CCLK_0':
      PIN_NUMBER='(L12,0,0,0,0)';
      OUTPUT_TYPE='(TS,TS)';
      BIDIRECTIONAL='TRUE';
      INPUT_LOAD='(-0.01,0.01)';
      OUTPUT_LOAD='(1.0,-1.0)';
      PINUSE='BI';
    'CFGBVS_0':
      PIN_NUMBER='(U8,0,0,0,0)';
      INPUT_LOAD='(-0.01,0.01)';
      PINUSE='IN';
    'DONE_0':
      PIN_NUMBER='(G11,0,0,0,0)';
      OUTPUT_TYPE='(TS,TS)';
      BIDIRECTIONAL='TRUE';
      INPUT_LOAD='(-0.01,0.01)';
      OUTPUT_LOAD='(1.0,-1.0)';
      PINUSE='BI';
    'DXN_0':
      PIN_NUMBER='(N9,0,0,0,0)';
      INPUT_LOAD='(-0.01,0.01)';
      PINUSE='IN';
    'DXP_0':
      PIN_NUMBER='(N10,0,0,0,0)';
      INPUT_LOAD='(-0.01,0.01)';
      PINUSE='IN';
    'INIT_0*':
      PIN_NUMBER='(U12,0,0,0,0)';
      OUTPUT_TYPE='(TS,TS)';
      BIDIRECTIONAL='TRUE';
      INPUT_LOAD='(-0.01,0.01)';
      OUTPUT_LOAD='(1.0,-1.0)';
      PINUSE='BI';
    'M0_0':
      PIN_NUMBER='(U11,0,0,0,0)';
      INPUT_LOAD='(-0.01,0.01)';
      PINUSE='IN';
    'M1_0':
      PIN_NUMBER='(U10,0,0,0,0)';
      INPUT_LOAD='(-0.01,0.01)';
      PINUSE='IN';
    'M2_0':
      PIN_NUMBER='(U9,0,0,0,0)';
      INPUT_LOAD='(-0.01,0.01)';
      PINUSE='IN';
    'MGTPRXN0_216':
      PIN_NUMBER='(A8,0,0,0,0)';
      INPUT_LOAD='(-0.01,0.01)';
      PINUSE='IN';
    'MGTPRXN1_216':
      PIN_NUMBER='(C11,0,0,0,0)';
      INPUT_LOAD='(-0.01,0.01)';
      PINUSE='IN';
    'MGTPRXN2_216':
      PIN_NUMBER='(A10,0,0,0,0)';
      INPUT_LOAD='(-0.01,0.01)';
      PINUSE='IN';
    'MGTPRXN3_216':
      PIN_NUMBER='(C9,0,0,0,0)';
      INPUT_LOAD='(-0.01,0.01)';
      PINUSE='IN';
    'MGTPRXP0_216':
      PIN_NUMBER='(B8,0,0,0,0)';
      INPUT_LOAD='(-0.01,0.01)';
      PINUSE='IN';
    'MGTPRXP1_216':
      PIN_NUMBER='(D11,0,0,0,0)';
      INPUT_LOAD='(-0.01,0.01)';
      PINUSE='IN';
    'MGTPRXP2_216':
      PIN_NUMBER='(B10,0,0,0,0)';
      INPUT_LOAD='(-0.01,0.01)';
      PINUSE='IN';
    'MGTPRXP3_216':
      PIN_NUMBER='(D9,0,0,0,0)';
      INPUT_LOAD='(-0.01,0.01)';
      PINUSE='IN';
    'MGTPTXN0_216':
      PIN_NUMBER='(A4,0,0,0,0)';
      OUTPUT_LOAD='(1.0,-1.0)';
      PINUSE='OUT';
    'MGTPTXN1_216':
      PIN_NUMBER='(C5,0,0,0,0)';
      OUTPUT_LOAD='(1.0,-1.0)';
      PINUSE='OUT';
    'MGTPTXN2_216':
      PIN_NUMBER='(A6,0,0,0,0)';
      OUTPUT_LOAD='(1.0,-1.0)';
      PINUSE='OUT';
    'MGTPTXN3_216':
      PIN_NUMBER='(C7,0,0,0,0)';
      OUTPUT_LOAD='(1.0,-1.0)';
      PINUSE='OUT';
    'MGTPTXP0_216':
      PIN_NUMBER='(B4,0,0,0,0)';
      OUTPUT_LOAD='(1.0,-1.0)';
      PINUSE='OUT';
    'MGTPTXP1_216':
      PIN_NUMBER='(D5,0,0,0,0)';
      OUTPUT_LOAD='(1.0,-1.0)';
      PINUSE='OUT';
    'MGTPTXP2_216':
      PIN_NUMBER='(B6,0,0,0,0)';
      OUTPUT_LOAD='(1.0,-1.0)';
      PINUSE='OUT';
    'MGTPTXP3_216':
      PIN_NUMBER='(D7,0,0,0,0)';
      OUTPUT_LOAD='(1.0,-1.0)';
      PINUSE='OUT';
    'MGTREFCLK0N_216':
      PIN_NUMBER='(E6,0,0,0,0)';
      INPUT_LOAD='(-0.01,0.01)';
      PINUSE='IN';
    'MGTREFCLK0P_216':
      PIN_NUMBER='(F6,0,0,0,0)';
      INPUT_LOAD='(-0.01,0.01)';
      PINUSE='IN';
    'MGTREFCLK1N_216':
      PIN_NUMBER='(E10,0,0,0,0)';
      INPUT_LOAD='(-0.01,0.01)';
      PINUSE='IN';
    'MGTREFCLK1P_216':
      PIN_NUMBER='(F10,0,0,0,0)';
      INPUT_LOAD='(-0.01,0.01)';
      PINUSE='IN';
    'MGTRREF_216':
      PIN_NUMBER='(F8,0,0,0,0)';
      INPUT_LOAD='(-0.01,0.01)';
      PINUSE='IN';
    'PROGRAM_0*':
      PIN_NUMBER='(N12,0,0,0,0)';
      OUTPUT_TYPE='(TS,TS)';
      BIDIRECTIONAL='TRUE';
      INPUT_LOAD='(-0.01,0.01)';
      OUTPUT_LOAD='(1.0,-1.0)';
      PINUSE='BI';
    'TCK_0':
      PIN_NUMBER='(V12,0,0,0,0)';
      INPUT_LOAD='(-0.01,0.01)';
      PINUSE='IN';
    'TDI_0':
      PIN_NUMBER='(R13,0,0,0,0)';
      INPUT_LOAD='(-0.01,0.01)';
      PINUSE='IN';
    'TDO_0':
      PIN_NUMBER='(U13,0,0,0,0)';
      OUTPUT_LOAD='(1.0,-1.0)';
      PINUSE='OUT';
    'TMS_0':
      PIN_NUMBER='(T13,0,0,0,0)';
      INPUT_LOAD='(-0.01,0.01)';
      PINUSE='IN';
    'VN_0':
      PIN_NUMBER='(M9,0,0,0,0)';
      INPUT_LOAD='(-0.01,0.01)';
      PINUSE='IN';
    'VP_0':
      PIN_NUMBER='(L10,0,0,0,0)';
      INPUT_LOAD='(-0.01,0.01)';
      PINUSE='IN';
    'VREFN_0':
      PIN_NUMBER='(L9,0,0,0,0)';
      OUTPUT_TYPE='(TS,TS)';
      BIDIRECTIONAL='TRUE';
      INPUT_LOAD='(-0.01,0.01)';
      OUTPUT_LOAD='(1.0,-1.0)';
      PINUSE='BI';
    'VREFP_0':
      PIN_NUMBER='(M10,0,0,0,0)';
      OUTPUT_TYPE='(TS,TS)';
      BIDIRECTIONAL='TRUE';
      INPUT_LOAD='(-0.01,0.01)';
      OUTPUT_LOAD='(1.0,-1.0)';
      PINUSE='BI';
    'IO_0_13':
      PIN_NUMBER='(0,Y17,0,0,0)';
      OUTPUT_TYPE='(TS,TS)';
      BIDIRECTIONAL='TRUE';
      INPUT_LOAD='(-0.01,0.01)';
      OUTPUT_LOAD='(1.0,-1.0)';
      PINUSE='BI';
    'IO_0_14':
      PIN_NUMBER='(0,P20,0,0,0)';
      OUTPUT_TYPE='(TS,TS)';
      BIDIRECTIONAL='TRUE';
      INPUT_LOAD='(-0.01,0.01)';
      OUTPUT_LOAD='(1.0,-1.0)';
      PINUSE='BI';
    'IO_25_14':
      PIN_NUMBER='(0,N15,0,0,0)';
      OUTPUT_TYPE='(TS,TS)';
      BIDIRECTIONAL='TRUE';
      INPUT_LOAD='(-0.01,0.01)';
      OUTPUT_LOAD='(1.0,-1.0)';
      PINUSE='BI';
    'IO_L1N_T0_13':
      PIN_NUMBER='(0,AA16,0,0,0)';
      OUTPUT_TYPE='(TS,TS)';
      BIDIRECTIONAL='TRUE';
      INPUT_LOAD='(-0.01,0.01)';
      OUTPUT_LOAD='(1.0,-1.0)';
      PINUSE='BI';
    'IO_L1N_T0_D01_DIN_14':
      PIN_NUMBER='(0,R22,0,0,0)';
      OUTPUT_TYPE='(TS,TS)';
      BIDIRECTIONAL='TRUE';
      INPUT_LOAD='(-0.01,0.01)';
      OUTPUT_LOAD='(1.0,-1.0)';
      PINUSE='BI';
    'IO_L1P_T0_13':
      PIN_NUMBER='(0,Y16,0,0,0)';
      OUTPUT_TYPE='(TS,TS)';
      BIDIRECTIONAL='TRUE';
      INPUT_LOAD='(-0.01,0.01)';
      OUTPUT_LOAD='(1.0,-1.0)';
      PINUSE='BI';
    'IO_L1P_T0_D00_MOSI_14':
      PIN_NUMBER='(0,P22,0,0,0)';
      OUTPUT_TYPE='(TS,TS)';
      BIDIRECTIONAL='TRUE';
      INPUT_LOAD='(-0.01,0.01)';
      OUTPUT_LOAD='(1.0,-1.0)';
      PINUSE='BI';
    'IO_L2N_T0_13':
      PIN_NUMBER='(0,AB17,0,0,0)';
      OUTPUT_TYPE='(TS,TS)';
      BIDIRECTIONAL='TRUE';
      INPUT_LOAD='(-0.01,0.01)';
      OUTPUT_LOAD='(1.0,-1.0)';
      PINUSE='BI';
    'IO_L2N_T0_D03_14':
      PIN_NUMBER='(0,R21,0,0,0)';
      OUTPUT_TYPE='(TS,TS)';
      BIDIRECTIONAL='TRUE';
      INPUT_LOAD='(-0.01,0.01)';
      OUTPUT_LOAD='(1.0,-1.0)';
      PINUSE='BI';
    'IO_L2P_T0_13':
      PIN_NUMBER='(0,AB16,0,0,0)';
      OUTPUT_TYPE='(TS,TS)';
      BIDIRECTIONAL='TRUE';
      INPUT_LOAD='(-0.01,0.01)';
      OUTPUT_LOAD='(1.0,-1.0)';
      PINUSE='BI';
    'IO_L2P_T0_D02_14':
      PIN_NUMBER='(0,P21,0,0,0)';
      OUTPUT_TYPE='(TS,TS)';
      BIDIRECTIONAL='TRUE';
      INPUT_LOAD='(-0.01,0.01)';
      OUTPUT_LOAD='(1.0,-1.0)';
      PINUSE='BI';
    'IO_L3N_T0_DQS_13':
      PIN_NUMBER='(0,AB13,0,0,0)';
      OUTPUT_TYPE='(TS,TS)';
      BIDIRECTIONAL='TRUE';
      INPUT_LOAD='(-0.01,0.01)';
      OUTPUT_LOAD='(1.0,-1.0)';
      PINUSE='BI';
    'IO_L3N_T0_DQS_EMCCLK_14':
      PIN_NUMBER='(0,V22,0,0,0)';
      OUTPUT_TYPE='(TS,TS)';
      BIDIRECTIONAL='TRUE';
      INPUT_LOAD='(-0.01,0.01)';
      OUTPUT_LOAD='(1.0,-1.0)';
      PINUSE='BI';
    'IO_L3P_T0_DQS_13':
      PIN_NUMBER='(0,AA13,0,0,0)';
      OUTPUT_TYPE='(TS,TS)';
      BIDIRECTIONAL='TRUE';
      INPUT_LOAD='(-0.01,0.01)';
      OUTPUT_LOAD='(1.0,-1.0)';
      PINUSE='BI';
    'IO_L3P_T0_DQS_PUDC_14*':
      PIN_NUMBER='(0,U22,0,0,0)';
      OUTPUT_TYPE='(TS,TS)';
      BIDIRECTIONAL='TRUE';
      INPUT_LOAD='(-0.01,0.01)';
      OUTPUT_LOAD='(1.0,-1.0)';
      PINUSE='BI';
    'IO_L4N_T0_13':
      PIN_NUMBER='(0,AB15,0,0,0)';
      OUTPUT_TYPE='(TS,TS)';
      BIDIRECTIONAL='TRUE';
      INPUT_LOAD='(-0.01,0.01)';
      OUTPUT_LOAD='(1.0,-1.0)';
      PINUSE='BI';
    'IO_L4N_T0_D05_14':
      PIN_NUMBER='(0,U21,0,0,0)';
      OUTPUT_TYPE='(TS,TS)';
      BIDIRECTIONAL='TRUE';
      INPUT_LOAD='(-0.01,0.01)';
      OUTPUT_LOAD='(1.0,-1.0)';
      PINUSE='BI';
    'IO_L4P_T0_13':
      PIN_NUMBER='(0,AA15,0,0,0)';
      OUTPUT_TYPE='(TS,TS)';
      BIDIRECTIONAL='TRUE';
      INPUT_LOAD='(-0.01,0.01)';
      OUTPUT_LOAD='(1.0,-1.0)';
      PINUSE='BI';
    'IO_L4P_T0_D04_14':
      PIN_NUMBER='(0,T21,0,0,0)';
      OUTPUT_TYPE='(TS,TS)';
      BIDIRECTIONAL='TRUE';
      INPUT_LOAD='(-0.01,0.01)';
      OUTPUT_LOAD='(1.0,-1.0)';
      PINUSE='BI';
    'IO_L5N_T0_13':
      PIN_NUMBER='(0,AA14,0,0,0)';
      OUTPUT_TYPE='(TS,TS)';
      BIDIRECTIONAL='TRUE';
      INPUT_LOAD='(-0.01,0.01)';
      OUTPUT_LOAD='(1.0,-1.0)';
      PINUSE='BI';
    'IO_L5N_T0_D07_14':
      PIN_NUMBER='(0,R19,0,0,0)';
      OUTPUT_TYPE='(TS,TS)';
      BIDIRECTIONAL='TRUE';
      INPUT_LOAD='(-0.01,0.01)';
      OUTPUT_LOAD='(1.0,-1.0)';
      PINUSE='BI';
    'IO_L5P_T0_13':
      PIN_NUMBER='(0,Y13,0,0,0)';
      OUTPUT_TYPE='(TS,TS)';
      BIDIRECTIONAL='TRUE';
      INPUT_LOAD='(-0.01,0.01)';
      OUTPUT_LOAD='(1.0,-1.0)';
      PINUSE='BI';
    'IO_L5P_T0_D06_14':
      PIN_NUMBER='(0,P19,0,0,0)';
      OUTPUT_TYPE='(TS,TS)';
      BIDIRECTIONAL='TRUE';
      INPUT_LOAD='(-0.01,0.01)';
      OUTPUT_LOAD='(1.0,-1.0)';
      PINUSE='BI';
    'IO_L6N_T0_D08_VREF_14':
      PIN_NUMBER='(0,T20,0,0,0)';
      OUTPUT_TYPE='(TS,TS)';
      BIDIRECTIONAL='TRUE';
      INPUT_LOAD='(-0.01,0.01)';
      OUTPUT_LOAD='(1.0,-1.0)';
      PINUSE='BI';
    'IO_L6N_T0_VREF_13':
      PIN_NUMBER='(0,Y14,0,0,0)';
      OUTPUT_TYPE='(TS,TS)';
      BIDIRECTIONAL='TRUE';
      INPUT_LOAD='(-0.01,0.01)';
      OUTPUT_LOAD='(1.0,-1.0)';
      PINUSE='BI';
    'IO_L6P_T0_13':
      PIN_NUMBER='(0,W14,0,0,0)';
      OUTPUT_TYPE='(TS,TS)';
      BIDIRECTIONAL='TRUE';
      INPUT_LOAD='(-0.01,0.01)';
      OUTPUT_LOAD='(1.0,-1.0)';
      PINUSE='BI';
    'IO_L6P_T0_FCS_B_14':
      PIN_NUMBER='(0,T19,0,0,0)';
      OUTPUT_TYPE='(TS,TS)';
      BIDIRECTIONAL='TRUE';
      INPUT_LOAD='(-0.01,0.01)';
      OUTPUT_LOAD='(1.0,-1.0)';
      PINUSE='BI';
    'IO_L7N_T1_13':
      PIN_NUMBER='(0,AB12,0,0,0)';
      OUTPUT_TYPE='(TS,TS)';
      BIDIRECTIONAL='TRUE';
      INPUT_LOAD='(-0.01,0.01)';
      OUTPUT_LOAD='(1.0,-1.0)';
      PINUSE='BI';
    'IO_L7N_T1_D10_14':
      PIN_NUMBER='(0,W22,0,0,0)';
      OUTPUT_TYPE='(TS,TS)';
      BIDIRECTIONAL='TRUE';
      INPUT_LOAD='(-0.01,0.01)';
      OUTPUT_LOAD='(1.0,-1.0)';
      PINUSE='BI';
    'IO_L7P_T1_13':
      PIN_NUMBER='(0,AB11,0,0,0)';
      OUTPUT_TYPE='(TS,TS)';
      BIDIRECTIONAL='TRUE';
      INPUT_LOAD='(-0.01,0.01)';
      OUTPUT_LOAD='(1.0,-1.0)';
      PINUSE='BI';
    'IO_L7P_T1_D09_14':
      PIN_NUMBER='(0,W21,0,0,0)';
      OUTPUT_TYPE='(TS,TS)';
      BIDIRECTIONAL='TRUE';
      INPUT_LOAD='(-0.01,0.01)';
      OUTPUT_LOAD='(1.0,-1.0)';
      PINUSE='BI';
    'IO_L8N_T1_13':
      PIN_NUMBER='(0,AB10,0,0,0)';
      OUTPUT_TYPE='(TS,TS)';
      BIDIRECTIONAL='TRUE';
      INPUT_LOAD='(-0.01,0.01)';
      OUTPUT_LOAD='(1.0,-1.0)';
      PINUSE='BI';
    'IO_L8N_T1_D12_14':
      PIN_NUMBER='(0,AA21,0,0,0)';
      OUTPUT_TYPE='(TS,TS)';
      BIDIRECTIONAL='TRUE';
      INPUT_LOAD='(-0.01,0.01)';
      OUTPUT_LOAD='(1.0,-1.0)';
      PINUSE='BI';
    'IO_L8P_T1_13':
      PIN_NUMBER='(0,AA9,0,0,0)';
      OUTPUT_TYPE='(TS,TS)';
      BIDIRECTIONAL='TRUE';
      INPUT_LOAD='(-0.01,0.01)';
      OUTPUT_LOAD='(1.0,-1.0)';
      PINUSE='BI';
    'IO_L8P_T1_D11_14':
      PIN_NUMBER='(0,AA20,0,0,0)';
      OUTPUT_TYPE='(TS,TS)';
      BIDIRECTIONAL='TRUE';
      INPUT_LOAD='(-0.01,0.01)';
      OUTPUT_LOAD='(1.0,-1.0)';
      PINUSE='BI';
    'IO_L9N_T1_DQS_13':
      PIN_NUMBER='(0,AA11,0,0,0)';
      OUTPUT_TYPE='(TS,TS)';
      BIDIRECTIONAL='TRUE';
      INPUT_LOAD='(-0.01,0.01)';
      OUTPUT_LOAD='(1.0,-1.0)';
      PINUSE='BI';
    'IO_L9N_T1_DQS_D13_14':
      PIN_NUMBER='(0,Y22,0,0,0)';
      OUTPUT_TYPE='(TS,TS)';
      BIDIRECTIONAL='TRUE';
      INPUT_LOAD='(-0.01,0.01)';
      OUTPUT_LOAD='(1.0,-1.0)';
      PINUSE='BI';
    'IO_L9P_T1_DQS_13':
      PIN_NUMBER='(0,AA10,0,0,0)';
      OUTPUT_TYPE='(TS,TS)';
      BIDIRECTIONAL='TRUE';
      INPUT_LOAD='(-0.01,0.01)';
      OUTPUT_LOAD='(1.0,-1.0)';
      PINUSE='BI';
    'IO_L9P_T1_DQS_14':
      PIN_NUMBER='(0,Y21,0,0,0)';
      OUTPUT_TYPE='(TS,TS)';
      BIDIRECTIONAL='TRUE';
      INPUT_LOAD='(-0.01,0.01)';
      OUTPUT_LOAD='(1.0,-1.0)';
      PINUSE='BI';
    'IO_L10N_T1_13':
      PIN_NUMBER='(0,W10,0,0,0)';
      OUTPUT_TYPE='(TS,TS)';
      BIDIRECTIONAL='TRUE';
      INPUT_LOAD='(-0.01,0.01)';
      OUTPUT_LOAD='(1.0,-1.0)';
      PINUSE='BI';
    'IO_L10N_T1_D15_14':
      PIN_NUMBER='(0,AB22,0,0,0)';
      OUTPUT_TYPE='(TS,TS)';
      BIDIRECTIONAL='TRUE';
      INPUT_LOAD='(-0.01,0.01)';
      OUTPUT_LOAD='(1.0,-1.0)';
      PINUSE='BI';
    'IO_L10P_T1_13':
      PIN_NUMBER='(0,V10,0,0,0)';
      OUTPUT_TYPE='(TS,TS)';
      BIDIRECTIONAL='TRUE';
      INPUT_LOAD='(-0.01,0.01)';
      OUTPUT_LOAD='(1.0,-1.0)';
      PINUSE='BI';
    'IO_L10P_T1_D14_14':
      PIN_NUMBER='(0,AB21,0,0,0)';
      OUTPUT_TYPE='(TS,TS)';
      BIDIRECTIONAL='TRUE';
      INPUT_LOAD='(-0.01,0.01)';
      OUTPUT_LOAD='(1.0,-1.0)';
      PINUSE='BI';
    'IO_L11N_T1_SRCC_13':
      PIN_NUMBER='(0,Y12,0,0,0)';
      OUTPUT_TYPE='(TS,TS)';
      BIDIRECTIONAL='TRUE';
      INPUT_LOAD='(-0.01,0.01)';
      OUTPUT_LOAD='(1.0,-1.0)';
      PINUSE='BI';
    'IO_L11N_T1_SRCC_14':
      PIN_NUMBER='(0,V20,0,0,0)';
      OUTPUT_TYPE='(TS,TS)';
      BIDIRECTIONAL='TRUE';
      INPUT_LOAD='(-0.01,0.01)';
      OUTPUT_LOAD='(1.0,-1.0)';
      PINUSE='BI';
    'IO_L11P_T1_SRCC_13':
      PIN_NUMBER='(0,Y11,0,0,0)';
      OUTPUT_TYPE='(TS,TS)';
      BIDIRECTIONAL='TRUE';
      INPUT_LOAD='(-0.01,0.01)';
      OUTPUT_LOAD='(1.0,-1.0)';
      PINUSE='BI';
    'IO_L11P_T1_SRCC_14':
      PIN_NUMBER='(0,U20,0,0,0)';
      OUTPUT_TYPE='(TS,TS)';
      BIDIRECTIONAL='TRUE';
      INPUT_LOAD='(-0.01,0.01)';
      OUTPUT_LOAD='(1.0,-1.0)';
      PINUSE='BI';
    'IO_L12N_T1_MRCC_13':
      PIN_NUMBER='(0,W12,0,0,0)';
      OUTPUT_TYPE='(TS,TS)';
      BIDIRECTIONAL='TRUE';
      INPUT_LOAD='(-0.01,0.01)';
      OUTPUT_LOAD='(1.0,-1.0)';
      PINUSE='BI';
    'IO_L12N_T1_MRCC_14':
      PIN_NUMBER='(0,W20,0,0,0)';
      OUTPUT_TYPE='(TS,TS)';
      BIDIRECTIONAL='TRUE';
      INPUT_LOAD='(-0.01,0.01)';
      OUTPUT_LOAD='(1.0,-1.0)';
      PINUSE='BI';
    'IO_L12P_T1_MRCC_13':
      PIN_NUMBER='(0,W11,0,0,0)';
      OUTPUT_TYPE='(TS,TS)';
      BIDIRECTIONAL='TRUE';
      INPUT_LOAD='(-0.01,0.01)';
      OUTPUT_LOAD='(1.0,-1.0)';
      PINUSE='BI';
    'IO_L12P_T1_MRCC_14':
      PIN_NUMBER='(0,W19,0,0,0)';
      OUTPUT_TYPE='(TS,TS)';
      BIDIRECTIONAL='TRUE';
      INPUT_LOAD='(-0.01,0.01)';
      OUTPUT_LOAD='(1.0,-1.0)';
      PINUSE='BI';
    'IO_L13N_T2_MRCC_13':
      PIN_NUMBER='(0,V14,0,0,0)';
      OUTPUT_TYPE='(TS,TS)';
      BIDIRECTIONAL='TRUE';
      INPUT_LOAD='(-0.01,0.01)';
      OUTPUT_LOAD='(1.0,-1.0)';
      PINUSE='BI';
    'IO_L13N_T2_MRCC_14':
      PIN_NUMBER='(0,Y19,0,0,0)';
      OUTPUT_TYPE='(TS,TS)';
      BIDIRECTIONAL='TRUE';
      INPUT_LOAD='(-0.01,0.01)';
      OUTPUT_LOAD='(1.0,-1.0)';
      PINUSE='BI';
    'IO_L13P_T2_MRCC_13':
      PIN_NUMBER='(0,V13,0,0,0)';
      OUTPUT_TYPE='(TS,TS)';
      BIDIRECTIONAL='TRUE';
      INPUT_LOAD='(-0.01,0.01)';
      OUTPUT_LOAD='(1.0,-1.0)';
      PINUSE='BI';
    'IO_L13P_T2_MRCC_14':
      PIN_NUMBER='(0,Y18,0,0,0)';
      OUTPUT_TYPE='(TS,TS)';
      BIDIRECTIONAL='TRUE';
      INPUT_LOAD='(-0.01,0.01)';
      OUTPUT_LOAD='(1.0,-1.0)';
      PINUSE='BI';
    'IO_L14N_T2_SRCC_13':
      PIN_NUMBER='(0,V15,0,0,0)';
      OUTPUT_TYPE='(TS,TS)';
      BIDIRECTIONAL='TRUE';
      INPUT_LOAD='(-0.01,0.01)';
      OUTPUT_LOAD='(1.0,-1.0)';
      PINUSE='BI';
    'IO_L14N_T2_SRCC_14':
      PIN_NUMBER='(0,V19,0,0,0)';
      OUTPUT_TYPE='(TS,TS)';
      BIDIRECTIONAL='TRUE';
      INPUT_LOAD='(-0.01,0.01)';
      OUTPUT_LOAD='(1.0,-1.0)';
      PINUSE='BI';
    'IO_L14P_T2_SRCC_13':
      PIN_NUMBER='(0,U15,0,0,0)';
      OUTPUT_TYPE='(TS,TS)';
      BIDIRECTIONAL='TRUE';
      INPUT_LOAD='(-0.01,0.01)';
      OUTPUT_LOAD='(1.0,-1.0)';
      PINUSE='BI';
    'IO_L14P_T2_SRCC_14':
      PIN_NUMBER='(0,V18,0,0,0)';
      OUTPUT_TYPE='(TS,TS)';
      BIDIRECTIONAL='TRUE';
      INPUT_LOAD='(-0.01,0.01)';
      OUTPUT_LOAD='(1.0,-1.0)';
      PINUSE='BI';
    'IO_L15N_T2_DQS_13':
      PIN_NUMBER='(0,T15,0,0,0)';
      OUTPUT_TYPE='(TS,TS)';
      BIDIRECTIONAL='TRUE';
      INPUT_LOAD='(-0.01,0.01)';
      OUTPUT_LOAD='(1.0,-1.0)';
      PINUSE='BI';
    'IO_L15N_T2_DQS_DOUT_CSO_14*':
      PIN_NUMBER='(0,AB20,0,0,0)';
      OUTPUT_TYPE='(TS,TS)';
      BIDIRECTIONAL='TRUE';
      INPUT_LOAD='(-0.01,0.01)';
      OUTPUT_LOAD='(1.0,-1.0)';
      PINUSE='BI';
    'IO_L15P_T2_DQS_13':
      PIN_NUMBER='(0,T14,0,0,0)';
      OUTPUT_TYPE='(TS,TS)';
      BIDIRECTIONAL='TRUE';
      INPUT_LOAD='(-0.01,0.01)';
      OUTPUT_LOAD='(1.0,-1.0)';
      PINUSE='BI';
    'IO_L15P_T2_DQS_RDWR_14*':
      PIN_NUMBER='(0,AA19,0,0,0)';
      OUTPUT_TYPE='(TS,TS)';
      BIDIRECTIONAL='TRUE';
      INPUT_LOAD='(-0.01,0.01)';
      OUTPUT_LOAD='(1.0,-1.0)';
      PINUSE='BI';
    'IO_L16N_T2_13':
      PIN_NUMBER='(0,W16,0,0,0)';
      OUTPUT_TYPE='(TS,TS)';
      BIDIRECTIONAL='TRUE';
      INPUT_LOAD='(-0.01,0.01)';
      OUTPUT_LOAD='(1.0,-1.0)';
      PINUSE='BI';
    'IO_L16N_T2_A15_D31_14':
      PIN_NUMBER='(0,W17,0,0,0)';
      OUTPUT_TYPE='(TS,TS)';
      BIDIRECTIONAL='TRUE';
      INPUT_LOAD='(-0.01,0.01)';
      OUTPUT_LOAD='(1.0,-1.0)';
      PINUSE='BI';
    'IO_L16P_T2_13':
      PIN_NUMBER='(0,W15,0,0,0)';
      OUTPUT_TYPE='(TS,TS)';
      BIDIRECTIONAL='TRUE';
      INPUT_LOAD='(-0.01,0.01)';
      OUTPUT_LOAD='(1.0,-1.0)';
      PINUSE='BI';
    'IO_L16P_T2_CSI_14*':
      PIN_NUMBER='(0,V17,0,0,0)';
      OUTPUT_TYPE='(TS,TS)';
      BIDIRECTIONAL='TRUE';
      INPUT_LOAD='(-0.01,0.01)';
      OUTPUT_LOAD='(1.0,-1.0)';
      PINUSE='BI';
    'IO_L17N_T2_13':
      PIN_NUMBER='(0,U16,0,0,0)';
      OUTPUT_TYPE='(TS,TS)';
      BIDIRECTIONAL='TRUE';
      INPUT_LOAD='(-0.01,0.01)';
      OUTPUT_LOAD='(1.0,-1.0)';
      PINUSE='BI';
    'IO_L17N_T2_A13_D29_14':
      PIN_NUMBER='(0,AB18,0,0,0)';
      OUTPUT_TYPE='(TS,TS)';
      BIDIRECTIONAL='TRUE';
      INPUT_LOAD='(-0.01,0.01)';
      OUTPUT_LOAD='(1.0,-1.0)';
      PINUSE='BI';
    'IO_L17P_T2_13':
      PIN_NUMBER='(0,T16,0,0,0)';
      OUTPUT_TYPE='(TS,TS)';
      BIDIRECTIONAL='TRUE';
      INPUT_LOAD='(-0.01,0.01)';
      OUTPUT_LOAD='(1.0,-1.0)';
      PINUSE='BI';
    'IO_L17P_T2_A14_D30_14':
      PIN_NUMBER='(0,AA18,0,0,0)';
      OUTPUT_TYPE='(TS,TS)';
      BIDIRECTIONAL='TRUE';
      INPUT_LOAD='(-0.01,0.01)';
      OUTPUT_LOAD='(1.0,-1.0)';
      PINUSE='BI';
    'IO_L18N_T2_A11_D27_14':
      PIN_NUMBER='(0,U18,0,0,0)';
      OUTPUT_TYPE='(TS,TS)';
      BIDIRECTIONAL='TRUE';
      INPUT_LOAD='(-0.01,0.01)';
      OUTPUT_LOAD='(1.0,-1.0)';
      PINUSE='BI';
    'IO_L18P_T2_A12_D28_14':
      PIN_NUMBER='(0,U17,0,0,0)';
      OUTPUT_TYPE='(TS,TS)';
      BIDIRECTIONAL='TRUE';
      INPUT_LOAD='(-0.01,0.01)';
      OUTPUT_LOAD='(1.0,-1.0)';
      PINUSE='BI';
    'IO_L19N_T3_A09_D25_VREF_14':
      PIN_NUMBER='(0,R14,0,0,0)';
      OUTPUT_TYPE='(TS,TS)';
      BIDIRECTIONAL='TRUE';
      INPUT_LOAD='(-0.01,0.01)';
      OUTPUT_LOAD='(1.0,-1.0)';
      PINUSE='BI';
    'IO_L19P_T3_A10_D26_14':
      PIN_NUMBER='(0,P14,0,0,0)';
      OUTPUT_TYPE='(TS,TS)';
      BIDIRECTIONAL='TRUE';
      INPUT_LOAD='(-0.01,0.01)';
      OUTPUT_LOAD='(1.0,-1.0)';
      PINUSE='BI';
    'IO_L20N_T3_A07_D23_14':
      PIN_NUMBER='(0,T18,0,0,0)';
      OUTPUT_TYPE='(TS,TS)';
      BIDIRECTIONAL='TRUE';
      INPUT_LOAD='(-0.01,0.01)';
      OUTPUT_LOAD='(1.0,-1.0)';
      PINUSE='BI';
    'IO_L20P_T3_A08_D24_14':
      PIN_NUMBER='(0,R18,0,0,0)';
      OUTPUT_TYPE='(TS,TS)';
      BIDIRECTIONAL='TRUE';
      INPUT_LOAD='(-0.01,0.01)';
      OUTPUT_LOAD='(1.0,-1.0)';
      PINUSE='BI';
    'IO_L21N_T3_DQS_A06_D22_14':
      PIN_NUMBER='(0,P17,0,0,0)';
      OUTPUT_TYPE='(TS,TS)';
      BIDIRECTIONAL='TRUE';
      INPUT_LOAD='(-0.01,0.01)';
      OUTPUT_LOAD='(1.0,-1.0)';
      PINUSE='BI';
    'IO_L21P_T3_DQS_14':
      PIN_NUMBER='(0,N17,0,0,0)';
      OUTPUT_TYPE='(TS,TS)';
      BIDIRECTIONAL='TRUE';
      INPUT_LOAD='(-0.01,0.01)';
      OUTPUT_LOAD='(1.0,-1.0)';
      PINUSE='BI';
    'IO_L22N_T3_A04_D20_14':
      PIN_NUMBER='(0,R16,0,0,0)';
      OUTPUT_TYPE='(TS,TS)';
      BIDIRECTIONAL='TRUE';
      INPUT_LOAD='(-0.01,0.01)';
      OUTPUT_LOAD='(1.0,-1.0)';
      PINUSE='BI';
    'IO_L22P_T3_A05_D21_14':
      PIN_NUMBER='(0,P15,0,0,0)';
      OUTPUT_TYPE='(TS,TS)';
      BIDIRECTIONAL='TRUE';
      INPUT_LOAD='(-0.01,0.01)';
      OUTPUT_LOAD='(1.0,-1.0)';
      PINUSE='BI';
    'IO_L23N_T3_A02_D18_14':
      PIN_NUMBER='(0,N14,0,0,0)';
      OUTPUT_TYPE='(TS,TS)';
      BIDIRECTIONAL='TRUE';
      INPUT_LOAD='(-0.01,0.01)';
      OUTPUT_LOAD='(1.0,-1.0)';
      PINUSE='BI';
    'IO_L23P_T3_A03_D19_14':
      PIN_NUMBER='(0,N13,0,0,0)';
      OUTPUT_TYPE='(TS,TS)';
      BIDIRECTIONAL='TRUE';
      INPUT_LOAD='(-0.01,0.01)';
      OUTPUT_LOAD='(1.0,-1.0)';
      PINUSE='BI';
    'IO_L24N_T3_A00_D16_14':
      PIN_NUMBER='(0,R17,0,0,0)';
      OUTPUT_TYPE='(TS,TS)';
      BIDIRECTIONAL='TRUE';
      INPUT_LOAD='(-0.01,0.01)';
      OUTPUT_LOAD='(1.0,-1.0)';
      PINUSE='BI';
    'IO_L24P_T3_A01_D17_14':
      PIN_NUMBER='(0,P16,0,0,0)';
      OUTPUT_TYPE='(TS,TS)';
      BIDIRECTIONAL='TRUE';
      INPUT_LOAD='(-0.01,0.01)';
      OUTPUT_LOAD='(1.0,-1.0)';
      PINUSE='BI';
    'IO_0_15':
      PIN_NUMBER='(0,0,J16,0,0)';
      OUTPUT_TYPE='(TS,TS)';
      BIDIRECTIONAL='TRUE';
      INPUT_LOAD='(-0.01,0.01)';
      OUTPUT_LOAD='(1.0,-1.0)';
      PINUSE='BI';
    'IO_0_16':
      PIN_NUMBER='(0,0,F15,0,0)';
      OUTPUT_TYPE='(TS,TS)';
      BIDIRECTIONAL='TRUE';
      INPUT_LOAD='(-0.01,0.01)';
      OUTPUT_LOAD='(1.0,-1.0)';
      PINUSE='BI';
    'IO_25_15':
      PIN_NUMBER='(0,0,M17,0,0)';
      OUTPUT_TYPE='(TS,TS)';
      BIDIRECTIONAL='TRUE';
      INPUT_LOAD='(-0.01,0.01)';
      OUTPUT_LOAD='(1.0,-1.0)';
      PINUSE='BI';
    'IO_25_16':
      PIN_NUMBER='(0,0,F21,0,0)';
      OUTPUT_TYPE='(TS,TS)';
      BIDIRECTIONAL='TRUE';
      INPUT_LOAD='(-0.01,0.01)';
      OUTPUT_LOAD='(1.0,-1.0)';
      PINUSE='BI';
    'IO_L1N_T0_16':
      PIN_NUMBER='(0,0,F14,0,0)';
      OUTPUT_TYPE='(TS,TS)';
      BIDIRECTIONAL='TRUE';
      INPUT_LOAD='(-0.01,0.01)';
      OUTPUT_LOAD='(1.0,-1.0)';
      PINUSE='BI';
    'IO_L1N_T0_AD0N_15':
      PIN_NUMBER='(0,0,G13,0,0)';
      OUTPUT_TYPE='(TS,TS)';
      BIDIRECTIONAL='TRUE';
      INPUT_LOAD='(-0.01,0.01)';
      OUTPUT_LOAD='(1.0,-1.0)';
      PINUSE='BI';
    'IO_L1P_T0_16':
      PIN_NUMBER='(0,0,F13,0,0)';
      OUTPUT_TYPE='(TS,TS)';
      BIDIRECTIONAL='TRUE';
      INPUT_LOAD='(-0.01,0.01)';
      OUTPUT_LOAD='(1.0,-1.0)';
      PINUSE='BI';
    'IO_L1P_T0_AD0P_15':
      PIN_NUMBER='(0,0,H13,0,0)';
      OUTPUT_TYPE='(TS,TS)';
      BIDIRECTIONAL='TRUE';
      INPUT_LOAD='(-0.01,0.01)';
      OUTPUT_LOAD='(1.0,-1.0)';
      PINUSE='BI';
    'IO_L2N_T0_16':
      PIN_NUMBER='(0,0,E17,0,0)';
      OUTPUT_TYPE='(TS,TS)';
      BIDIRECTIONAL='TRUE';
      INPUT_LOAD='(-0.01,0.01)';
      OUTPUT_LOAD='(1.0,-1.0)';
      PINUSE='BI';
    'IO_L2N_T0_AD8N_15':
      PIN_NUMBER='(0,0,G16,0,0)';
      OUTPUT_TYPE='(TS,TS)';
      BIDIRECTIONAL='TRUE';
      INPUT_LOAD='(-0.01,0.01)';
      OUTPUT_LOAD='(1.0,-1.0)';
      PINUSE='BI';
    'IO_L2P_T0_16':
      PIN_NUMBER='(0,0,F16,0,0)';
      OUTPUT_TYPE='(TS,TS)';
      BIDIRECTIONAL='TRUE';
      INPUT_LOAD='(-0.01,0.01)';
      OUTPUT_LOAD='(1.0,-1.0)';
      PINUSE='BI';
    'IO_L2P_T0_AD8P_15':
      PIN_NUMBER='(0,0,G15,0,0)';
      OUTPUT_TYPE='(TS,TS)';
      BIDIRECTIONAL='TRUE';
      INPUT_LOAD='(-0.01,0.01)';
      OUTPUT_LOAD='(1.0,-1.0)';
      PINUSE='BI';
    'IO_L3N_T0_DQS_16':
      PIN_NUMBER='(0,0,C15,0,0)';
      OUTPUT_TYPE='(TS,TS)';
      BIDIRECTIONAL='TRUE';
      INPUT_LOAD='(-0.01,0.01)';
      OUTPUT_LOAD='(1.0,-1.0)';
      PINUSE='BI';
    'IO_L3N_T0_DQS_AD1N_15':
      PIN_NUMBER='(0,0,H14,0,0)';
      OUTPUT_TYPE='(TS,TS)';
      BIDIRECTIONAL='TRUE';
      INPUT_LOAD='(-0.01,0.01)';
      OUTPUT_LOAD='(1.0,-1.0)';
      PINUSE='BI';
    'IO_L3P_T0_DQS_16':
      PIN_NUMBER='(0,0,C14,0,0)';
      OUTPUT_TYPE='(TS,TS)';
      BIDIRECTIONAL='TRUE';
      INPUT_LOAD='(-0.01,0.01)';
      OUTPUT_LOAD='(1.0,-1.0)';
      PINUSE='BI';
    'IO_L3P_T0_DQS_AD1P_15':
      PIN_NUMBER='(0,0,J14,0,0)';
      OUTPUT_TYPE='(TS,TS)';
      BIDIRECTIONAL='TRUE';
      INPUT_LOAD='(-0.01,0.01)';
      OUTPUT_LOAD='(1.0,-1.0)';
      PINUSE='BI';
    'IO_L4N_T0_15':
      PIN_NUMBER='(0,0,G18,0,0)';
      OUTPUT_TYPE='(TS,TS)';
      BIDIRECTIONAL='TRUE';
      INPUT_LOAD='(-0.01,0.01)';
      OUTPUT_LOAD='(1.0,-1.0)';
      PINUSE='BI';
    'IO_L4N_T0_16':
      PIN_NUMBER='(0,0,E14,0,0)';
      OUTPUT_TYPE='(TS,TS)';
      BIDIRECTIONAL='TRUE';
      INPUT_LOAD='(-0.01,0.01)';
      OUTPUT_LOAD='(1.0,-1.0)';
      PINUSE='BI';
    'IO_L4P_T0_15':
      PIN_NUMBER='(0,0,G17,0,0)';
      OUTPUT_TYPE='(TS,TS)';
      BIDIRECTIONAL='TRUE';
      INPUT_LOAD='(-0.01,0.01)';
      OUTPUT_LOAD='(1.0,-1.0)';
      PINUSE='BI';
    'IO_L4P_T0_16':
      PIN_NUMBER='(0,0,E13,0,0)';
      OUTPUT_TYPE='(TS,TS)';
      BIDIRECTIONAL='TRUE';
      INPUT_LOAD='(-0.01,0.01)';
      OUTPUT_LOAD='(1.0,-1.0)';
      PINUSE='BI';
    'IO_L5N_T0_16':
      PIN_NUMBER='(0,0,D16,0,0)';
      OUTPUT_TYPE='(TS,TS)';
      BIDIRECTIONAL='TRUE';
      INPUT_LOAD='(-0.01,0.01)';
      OUTPUT_LOAD='(1.0,-1.0)';
      PINUSE='BI';
    'IO_L5N_T0_AD9N_15':
      PIN_NUMBER='(0,0,H15,0,0)';
      OUTPUT_TYPE='(TS,TS)';
      BIDIRECTIONAL='TRUE';
      INPUT_LOAD='(-0.01,0.01)';
      OUTPUT_LOAD='(1.0,-1.0)';
      PINUSE='BI';
    'IO_L5P_T0_16':
      PIN_NUMBER='(0,0,E16,0,0)';
      OUTPUT_TYPE='(TS,TS)';
      BIDIRECTIONAL='TRUE';
      INPUT_LOAD='(-0.01,0.01)';
      OUTPUT_LOAD='(1.0,-1.0)';
      PINUSE='BI';
    'IO_L5P_T0_AD9P_15':
      PIN_NUMBER='(0,0,J15,0,0)';
      OUTPUT_TYPE='(TS,TS)';
      BIDIRECTIONAL='TRUE';
      INPUT_LOAD='(-0.01,0.01)';
      OUTPUT_LOAD='(1.0,-1.0)';
      PINUSE='BI';
    'IO_L6N_T0_VREF_15':
      PIN_NUMBER='(0,0,H18,0,0)';
      OUTPUT_TYPE='(TS,TS)';
      BIDIRECTIONAL='TRUE';
      INPUT_LOAD='(-0.01,0.01)';
      OUTPUT_LOAD='(1.0,-1.0)';
      PINUSE='BI';
    'IO_L6N_T0_VREF_16':
      PIN_NUMBER='(0,0,D15,0,0)';
      OUTPUT_TYPE='(TS,TS)';
      BIDIRECTIONAL='TRUE';
      INPUT_LOAD='(-0.01,0.01)';
      OUTPUT_LOAD='(1.0,-1.0)';
      PINUSE='BI';
    'IO_L6P_T0_15':
      PIN_NUMBER='(0,0,H17,0,0)';
      OUTPUT_TYPE='(TS,TS)';
      BIDIRECTIONAL='TRUE';
      INPUT_LOAD='(-0.01,0.01)';
      OUTPUT_LOAD='(1.0,-1.0)';
      PINUSE='BI';
    'IO_L6P_T0_16':
      PIN_NUMBER='(0,0,D14,0,0)';
      OUTPUT_TYPE='(TS,TS)';
      BIDIRECTIONAL='TRUE';
      INPUT_LOAD='(-0.01,0.01)';
      OUTPUT_LOAD='(1.0,-1.0)';
      PINUSE='BI';
    'IO_L7N_T1_16':
      PIN_NUMBER='(0,0,B16,0,0)';
      OUTPUT_TYPE='(TS,TS)';
      BIDIRECTIONAL='TRUE';
      INPUT_LOAD='(-0.01,0.01)';
      OUTPUT_LOAD='(1.0,-1.0)';
      PINUSE='BI';
    'IO_L7N_T1_AD2N_15':
      PIN_NUMBER='(0,0,H22,0,0)';
      OUTPUT_TYPE='(TS,TS)';
      BIDIRECTIONAL='TRUE';
      INPUT_LOAD='(-0.01,0.01)';
      OUTPUT_LOAD='(1.0,-1.0)';
      PINUSE='BI';
    'IO_L7P_T1_16':
      PIN_NUMBER='(0,0,B15,0,0)';
      OUTPUT_TYPE='(TS,TS)';
      BIDIRECTIONAL='TRUE';
      INPUT_LOAD='(-0.01,0.01)';
      OUTPUT_LOAD='(1.0,-1.0)';
      PINUSE='BI';
    'IO_L7P_T1_AD2P_15':
      PIN_NUMBER='(0,0,J22,0,0)';
      OUTPUT_TYPE='(TS,TS)';
      BIDIRECTIONAL='TRUE';
      INPUT_LOAD='(-0.01,0.01)';
      OUTPUT_LOAD='(1.0,-1.0)';
      PINUSE='BI';
    'IO_L8N_T1_16':
      PIN_NUMBER='(0,0,B13,0,0)';
      OUTPUT_TYPE='(TS,TS)';
      BIDIRECTIONAL='TRUE';
      INPUT_LOAD='(-0.01,0.01)';
      OUTPUT_LOAD='(1.0,-1.0)';
      PINUSE='BI';
    'IO_L8N_T1_AD10N_15':
      PIN_NUMBER='(0,0,G20,0,0)';
      OUTPUT_TYPE='(TS,TS)';
      BIDIRECTIONAL='TRUE';
      INPUT_LOAD='(-0.01,0.01)';
      OUTPUT_LOAD='(1.0,-1.0)';
      PINUSE='BI';
    'IO_L8P_T1_16':
      PIN_NUMBER='(0,0,C13,0,0)';
      OUTPUT_TYPE='(TS,TS)';
      BIDIRECTIONAL='TRUE';
      INPUT_LOAD='(-0.01,0.01)';
      OUTPUT_LOAD='(1.0,-1.0)';
      PINUSE='BI';
    'IO_L8P_T1_AD10P_15':
      PIN_NUMBER='(0,0,H20,0,0)';
      OUTPUT_TYPE='(TS,TS)';
      BIDIRECTIONAL='TRUE';
      INPUT_LOAD='(-0.01,0.01)';
      OUTPUT_LOAD='(1.0,-1.0)';
      PINUSE='BI';
    'IO_L9N_T1_DQS_16':
      PIN_NUMBER='(0,0,A16,0,0)';
      OUTPUT_TYPE='(TS,TS)';
      BIDIRECTIONAL='TRUE';
      INPUT_LOAD='(-0.01,0.01)';
      OUTPUT_LOAD='(1.0,-1.0)';
      PINUSE='BI';
    'IO_L9N_T1_DQS_AD3N_15':
      PIN_NUMBER='(0,0,K22,0,0)';
      OUTPUT_TYPE='(TS,TS)';
      BIDIRECTIONAL='TRUE';
      INPUT_LOAD='(-0.01,0.01)';
      OUTPUT_LOAD='(1.0,-1.0)';
      PINUSE='BI';
    'IO_L9P_T1_DQS_16':
      PIN_NUMBER='(0,0,A15,0,0)';
      OUTPUT_TYPE='(TS,TS)';
      BIDIRECTIONAL='TRUE';
      INPUT_LOAD='(-0.01,0.01)';
      OUTPUT_LOAD='(1.0,-1.0)';
      PINUSE='BI';
    'IO_L9P_T1_DQS_AD3P_15':
      PIN_NUMBER='(0,0,K21,0,0)';
      OUTPUT_TYPE='(TS,TS)';
      BIDIRECTIONAL='TRUE';
      INPUT_LOAD='(-0.01,0.01)';
      OUTPUT_LOAD='(1.0,-1.0)';
      PINUSE='BI';
    'IO_L10N_T1_16':
      PIN_NUMBER='(0,0,A14,0,0)';
      OUTPUT_TYPE='(TS,TS)';
      BIDIRECTIONAL='TRUE';
      INPUT_LOAD='(-0.01,0.01)';
      OUTPUT_LOAD='(1.0,-1.0)';
      PINUSE='BI';
    'IO_L10N_T1_AD11N_15':
      PIN_NUMBER='(0,0,L21,0,0)';
      OUTPUT_TYPE='(TS,TS)';
      BIDIRECTIONAL='TRUE';
      INPUT_LOAD='(-0.01,0.01)';
      OUTPUT_LOAD='(1.0,-1.0)';
      PINUSE='BI';
    'IO_L10P_T1_16':
      PIN_NUMBER='(0,0,A13,0,0)';
      OUTPUT_TYPE='(TS,TS)';
      BIDIRECTIONAL='TRUE';
      INPUT_LOAD='(-0.01,0.01)';
      OUTPUT_LOAD='(1.0,-1.0)';
      PINUSE='BI';
    'IO_L10P_T1_AD11P_15':
      PIN_NUMBER='(0,0,M21,0,0)';
      OUTPUT_TYPE='(TS,TS)';
      BIDIRECTIONAL='TRUE';
      INPUT_LOAD='(-0.01,0.01)';
      OUTPUT_LOAD='(1.0,-1.0)';
      PINUSE='BI';
    'IO_L11N_T1_SRCC_15':
      PIN_NUMBER='(0,0,J21,0,0)';
      OUTPUT_TYPE='(TS,TS)';
      BIDIRECTIONAL='TRUE';
      INPUT_LOAD='(-0.01,0.01)';
      OUTPUT_LOAD='(1.0,-1.0)';
      PINUSE='BI';
    'IO_L11N_T1_SRCC_16':
      PIN_NUMBER='(0,0,B18,0,0)';
      OUTPUT_TYPE='(TS,TS)';
      BIDIRECTIONAL='TRUE';
      INPUT_LOAD='(-0.01,0.01)';
      OUTPUT_LOAD='(1.0,-1.0)';
      PINUSE='BI';
    'IO_L11P_T1_SRCC_15':
      PIN_NUMBER='(0,0,J20,0,0)';
      OUTPUT_TYPE='(TS,TS)';
      BIDIRECTIONAL='TRUE';
      INPUT_LOAD='(-0.01,0.01)';
      OUTPUT_LOAD='(1.0,-1.0)';
      PINUSE='BI';
    'IO_L11P_T1_SRCC_16':
      PIN_NUMBER='(0,0,B17,0,0)';
      OUTPUT_TYPE='(TS,TS)';
      BIDIRECTIONAL='TRUE';
      INPUT_LOAD='(-0.01,0.01)';
      OUTPUT_LOAD='(1.0,-1.0)';
      PINUSE='BI';
    'IO_L12N_T1_MRCC_15':
      PIN_NUMBER='(0,0,H19,0,0)';
      OUTPUT_TYPE='(TS,TS)';
      BIDIRECTIONAL='TRUE';
      INPUT_LOAD='(-0.01,0.01)';
      OUTPUT_LOAD='(1.0,-1.0)';
      PINUSE='BI';
    'IO_L12N_T1_MRCC_16':
      PIN_NUMBER='(0,0,C17,0,0)';
      OUTPUT_TYPE='(TS,TS)';
      BIDIRECTIONAL='TRUE';
      INPUT_LOAD='(-0.01,0.01)';
      OUTPUT_LOAD='(1.0,-1.0)';
      PINUSE='BI';
    'IO_L12P_T1_MRCC_15':
      PIN_NUMBER='(0,0,J19,0,0)';
      OUTPUT_TYPE='(TS,TS)';
      BIDIRECTIONAL='TRUE';
      INPUT_LOAD='(-0.01,0.01)';
      OUTPUT_LOAD='(1.0,-1.0)';
      PINUSE='BI';
    'IO_L12P_T1_MRCC_16':
      PIN_NUMBER='(0,0,D17,0,0)';
      OUTPUT_TYPE='(TS,TS)';
      BIDIRECTIONAL='TRUE';
      INPUT_LOAD='(-0.01,0.01)';
      OUTPUT_LOAD='(1.0,-1.0)';
      PINUSE='BI';
    'IO_L13N_T2_MRCC_15':
      PIN_NUMBER='(0,0,K19,0,0)';
      OUTPUT_TYPE='(TS,TS)';
      BIDIRECTIONAL='TRUE';
      INPUT_LOAD='(-0.01,0.01)';
      OUTPUT_LOAD='(1.0,-1.0)';
      PINUSE='BI';
    'IO_L13N_T2_MRCC_16':
      PIN_NUMBER='(0,0,C19,0,0)';
      OUTPUT_TYPE='(TS,TS)';
      BIDIRECTIONAL='TRUE';
      INPUT_LOAD='(-0.01,0.01)';
      OUTPUT_LOAD='(1.0,-1.0)';
      PINUSE='BI';
    'IO_L13P_T2_MRCC_15':
      PIN_NUMBER='(0,0,K18,0,0)';
      OUTPUT_TYPE='(TS,TS)';
      BIDIRECTIONAL='TRUE';
      INPUT_LOAD='(-0.01,0.01)';
      OUTPUT_LOAD='(1.0,-1.0)';
      PINUSE='BI';
    'IO_L13P_T2_MRCC_16':
      PIN_NUMBER='(0,0,C18,0,0)';
      OUTPUT_TYPE='(TS,TS)';
      BIDIRECTIONAL='TRUE';
      INPUT_LOAD='(-0.01,0.01)';
      OUTPUT_LOAD='(1.0,-1.0)';
      PINUSE='BI';
    'IO_L14N_T2_SRCC_15':
      PIN_NUMBER='(0,0,L20,0,0)';
      OUTPUT_TYPE='(TS,TS)';
      BIDIRECTIONAL='TRUE';
      INPUT_LOAD='(-0.01,0.01)';
      OUTPUT_LOAD='(1.0,-1.0)';
      PINUSE='BI';
    'IO_L14N_T2_SRCC_16':
      PIN_NUMBER='(0,0,D19,0,0)';
      OUTPUT_TYPE='(TS,TS)';
      BIDIRECTIONAL='TRUE';
      INPUT_LOAD='(-0.01,0.01)';
      OUTPUT_LOAD='(1.0,-1.0)';
      PINUSE='BI';
    'IO_L14P_T2_SRCC_15':
      PIN_NUMBER='(0,0,L19,0,0)';
      OUTPUT_TYPE='(TS,TS)';
      BIDIRECTIONAL='TRUE';
      INPUT_LOAD='(-0.01,0.01)';
      OUTPUT_LOAD='(1.0,-1.0)';
      PINUSE='BI';
    'IO_L14P_T2_SRCC_16':
      PIN_NUMBER='(0,0,E19,0,0)';
      OUTPUT_TYPE='(TS,TS)';
      BIDIRECTIONAL='TRUE';
      INPUT_LOAD='(-0.01,0.01)';
      OUTPUT_LOAD='(1.0,-1.0)';
      PINUSE='BI';
    'IO_L15N_T2_DQS_16':
      PIN_NUMBER='(0,0,E18,0,0)';
      OUTPUT_TYPE='(TS,TS)';
      BIDIRECTIONAL='TRUE';
      INPUT_LOAD='(-0.01,0.01)';
      OUTPUT_LOAD='(1.0,-1.0)';
      PINUSE='BI';
    'IO_L15N_T2_DQS_ADV_B_15':
      PIN_NUMBER='(0,0,M22,0,0)';
      OUTPUT_TYPE='(TS,TS)';
      BIDIRECTIONAL='TRUE';
      INPUT_LOAD='(-0.01,0.01)';
      OUTPUT_LOAD='(1.0,-1.0)';
      PINUSE='BI';
    'IO_L15P_T2_DQS_15':
      PIN_NUMBER='(0,0,N22,0,0)';
      OUTPUT_TYPE='(TS,TS)';
      BIDIRECTIONAL='TRUE';
      INPUT_LOAD='(-0.01,0.01)';
      OUTPUT_LOAD='(1.0,-1.0)';
      PINUSE='BI';
    'IO_L15P_T2_DQS_16':
      PIN_NUMBER='(0,0,F18,0,0)';
      OUTPUT_TYPE='(TS,TS)';
      BIDIRECTIONAL='TRUE';
      INPUT_LOAD='(-0.01,0.01)';
      OUTPUT_LOAD='(1.0,-1.0)';
      PINUSE='BI';
    'IO_L16N_T2_16':
      PIN_NUMBER='(0,0,A20,0,0)';
      OUTPUT_TYPE='(TS,TS)';
      BIDIRECTIONAL='TRUE';
      INPUT_LOAD='(-0.01,0.01)';
      OUTPUT_LOAD='(1.0,-1.0)';
      PINUSE='BI';
    'IO_L16N_T2_A27_15':
      PIN_NUMBER='(0,0,L18,0,0)';
      OUTPUT_TYPE='(TS,TS)';
      BIDIRECTIONAL='TRUE';
      INPUT_LOAD='(-0.01,0.01)';
      OUTPUT_LOAD='(1.0,-1.0)';
      PINUSE='BI';
    'IO_L16P_T2_16':
      PIN_NUMBER='(0,0,B20,0,0)';
      OUTPUT_TYPE='(TS,TS)';
      BIDIRECTIONAL='TRUE';
      INPUT_LOAD='(-0.01,0.01)';
      OUTPUT_LOAD='(1.0,-1.0)';
      PINUSE='BI';
    'IO_L16P_T2_A28_15':
      PIN_NUMBER='(0,0,M18,0,0)';
      OUTPUT_TYPE='(TS,TS)';
      BIDIRECTIONAL='TRUE';
      INPUT_LOAD='(-0.01,0.01)';
      OUTPUT_LOAD='(1.0,-1.0)';
      PINUSE='BI';
    'IO_L17N_T2_16':
      PIN_NUMBER='(0,0,A19,0,0)';
      OUTPUT_TYPE='(TS,TS)';
      BIDIRECTIONAL='TRUE';
      INPUT_LOAD='(-0.01,0.01)';
      OUTPUT_LOAD='(1.0,-1.0)';
      PINUSE='BI';
    'IO_L17N_T2_A25_15':
      PIN_NUMBER='(0,0,N19,0,0)';
      OUTPUT_TYPE='(TS,TS)';
      BIDIRECTIONAL='TRUE';
      INPUT_LOAD='(-0.01,0.01)';
      OUTPUT_LOAD='(1.0,-1.0)';
      PINUSE='BI';
    'IO_L17P_T2_16':
      PIN_NUMBER='(0,0,A18,0,0)';
      OUTPUT_TYPE='(TS,TS)';
      BIDIRECTIONAL='TRUE';
      INPUT_LOAD='(-0.01,0.01)';
      OUTPUT_LOAD='(1.0,-1.0)';
      PINUSE='BI';
    'IO_L17P_T2_A26_15':
      PIN_NUMBER='(0,0,N18,0,0)';
      OUTPUT_TYPE='(TS,TS)';
      BIDIRECTIONAL='TRUE';
      INPUT_LOAD='(-0.01,0.01)';
      OUTPUT_LOAD='(1.0,-1.0)';
      PINUSE='BI';
    'IO_L18N_T2_16':
      PIN_NUMBER='(0,0,F20,0,0)';
      OUTPUT_TYPE='(TS,TS)';
      BIDIRECTIONAL='TRUE';
      INPUT_LOAD='(-0.01,0.01)';
      OUTPUT_LOAD='(1.0,-1.0)';
      PINUSE='BI';
    'IO_L18N_T2_A23_15':
      PIN_NUMBER='(0,0,M20,0,0)';
      OUTPUT_TYPE='(TS,TS)';
      BIDIRECTIONAL='TRUE';
      INPUT_LOAD='(-0.01,0.01)';
      OUTPUT_LOAD='(1.0,-1.0)';
      PINUSE='BI';
    'IO_L18P_T2_16':
      PIN_NUMBER='(0,0,F19,0,0)';
      OUTPUT_TYPE='(TS,TS)';
      BIDIRECTIONAL='TRUE';
      INPUT_LOAD='(-0.01,0.01)';
      OUTPUT_LOAD='(1.0,-1.0)';
      PINUSE='BI';
    'IO_L18P_T2_A24_15':
      PIN_NUMBER='(0,0,N20,0,0)';
      OUTPUT_TYPE='(TS,TS)';
      BIDIRECTIONAL='TRUE';
      INPUT_LOAD='(-0.01,0.01)';
      OUTPUT_LOAD='(1.0,-1.0)';
      PINUSE='BI';
    'IO_L19N_T3_A21_VREF_15':
      PIN_NUMBER='(0,0,K14,0,0)';
      OUTPUT_TYPE='(TS,TS)';
      BIDIRECTIONAL='TRUE';
      INPUT_LOAD='(-0.01,0.01)';
      OUTPUT_LOAD='(1.0,-1.0)';
      PINUSE='BI';
    'IO_L19N_T3_VREF_16':
      PIN_NUMBER='(0,0,C20,0,0)';
      OUTPUT_TYPE='(TS,TS)';
      BIDIRECTIONAL='TRUE';
      INPUT_LOAD='(-0.01,0.01)';
      OUTPUT_LOAD='(1.0,-1.0)';
      PINUSE='BI';
    'IO_L19P_T3_16':
      PIN_NUMBER='(0,0,D20,0,0)';
      OUTPUT_TYPE='(TS,TS)';
      BIDIRECTIONAL='TRUE';
      INPUT_LOAD='(-0.01,0.01)';
      OUTPUT_LOAD='(1.0,-1.0)';
      PINUSE='BI';
    'IO_L19P_T3_A22_15':
      PIN_NUMBER='(0,0,K13,0,0)';
      OUTPUT_TYPE='(TS,TS)';
      BIDIRECTIONAL='TRUE';
      INPUT_LOAD='(-0.01,0.01)';
      OUTPUT_LOAD='(1.0,-1.0)';
      PINUSE='BI';
    'IO_L20N_T3_16':
      PIN_NUMBER='(0,0,B22,0,0)';
      OUTPUT_TYPE='(TS,TS)';
      BIDIRECTIONAL='TRUE';
      INPUT_LOAD='(-0.01,0.01)';
      OUTPUT_LOAD='(1.0,-1.0)';
      PINUSE='BI';
    'IO_L20N_T3_A19_15':
      PIN_NUMBER='(0,0,L13,0,0)';
      OUTPUT_TYPE='(TS,TS)';
      BIDIRECTIONAL='TRUE';
      INPUT_LOAD='(-0.01,0.01)';
      OUTPUT_LOAD='(1.0,-1.0)';
      PINUSE='BI';
    'IO_L20P_T3_16':
      PIN_NUMBER='(0,0,C22,0,0)';
      OUTPUT_TYPE='(TS,TS)';
      BIDIRECTIONAL='TRUE';
      INPUT_LOAD='(-0.01,0.01)';
      OUTPUT_LOAD='(1.0,-1.0)';
      PINUSE='BI';
    'IO_L20P_T3_A20_15':
      PIN_NUMBER='(0,0,M13,0,0)';
      OUTPUT_TYPE='(TS,TS)';
      BIDIRECTIONAL='TRUE';
      INPUT_LOAD='(-0.01,0.01)';
      OUTPUT_LOAD='(1.0,-1.0)';
      PINUSE='BI';
    'IO_L21N_T3_DQS_16':
      PIN_NUMBER='(0,0,A21,0,0)';
      OUTPUT_TYPE='(TS,TS)';
      BIDIRECTIONAL='TRUE';
      INPUT_LOAD='(-0.01,0.01)';
      OUTPUT_LOAD='(1.0,-1.0)';
      PINUSE='BI';
    'IO_L21N_T3_DQS_A18_15':
      PIN_NUMBER='(0,0,J17,0,0)';
      OUTPUT_TYPE='(TS,TS)';
      BIDIRECTIONAL='TRUE';
      INPUT_LOAD='(-0.01,0.01)';
      OUTPUT_LOAD='(1.0,-1.0)';
      PINUSE='BI';
    'IO_L21P_T3_DQS_15':
      PIN_NUMBER='(0,0,K17,0,0)';
      OUTPUT_TYPE='(TS,TS)';
      BIDIRECTIONAL='TRUE';
      INPUT_LOAD='(-0.01,0.01)';
      OUTPUT_LOAD='(1.0,-1.0)';
      PINUSE='BI';
    'IO_L21P_T3_DQS_16':
      PIN_NUMBER='(0,0,B21,0,0)';
      OUTPUT_TYPE='(TS,TS)';
      BIDIRECTIONAL='TRUE';
      INPUT_LOAD='(-0.01,0.01)';
      OUTPUT_LOAD='(1.0,-1.0)';
      PINUSE='BI';
    'IO_L22N_T3_16':
      PIN_NUMBER='(0,0,D22,0,0)';
      OUTPUT_TYPE='(TS,TS)';
      BIDIRECTIONAL='TRUE';
      INPUT_LOAD='(-0.01,0.01)';
      OUTPUT_LOAD='(1.0,-1.0)';
      PINUSE='BI';
    'IO_L22N_T3_A16_15':
      PIN_NUMBER='(0,0,L15,0,0)';
      OUTPUT_TYPE='(TS,TS)';
      BIDIRECTIONAL='TRUE';
      INPUT_LOAD='(-0.01,0.01)';
      OUTPUT_LOAD='(1.0,-1.0)';
      PINUSE='BI';
    'IO_L22P_T3_16':
      PIN_NUMBER='(0,0,E22,0,0)';
      OUTPUT_TYPE='(TS,TS)';
      BIDIRECTIONAL='TRUE';
      INPUT_LOAD='(-0.01,0.01)';
      OUTPUT_LOAD='(1.0,-1.0)';
      PINUSE='BI';
    'IO_L22P_T3_A17_15':
      PIN_NUMBER='(0,0,L14,0,0)';
      OUTPUT_TYPE='(TS,TS)';
      BIDIRECTIONAL='TRUE';
      INPUT_LOAD='(-0.01,0.01)';
      OUTPUT_LOAD='(1.0,-1.0)';
      PINUSE='BI';
    'IO_L23N_T3_16':
      PIN_NUMBER='(0,0,D21,0,0)';
      OUTPUT_TYPE='(TS,TS)';
      BIDIRECTIONAL='TRUE';
      INPUT_LOAD='(-0.01,0.01)';
      OUTPUT_LOAD='(1.0,-1.0)';
      PINUSE='BI';
    'IO_L23N_T3_FWE_B_15':
      PIN_NUMBER='(0,0,K16,0,0)';
      OUTPUT_TYPE='(TS,TS)';
      BIDIRECTIONAL='TRUE';
      INPUT_LOAD='(-0.01,0.01)';
      OUTPUT_LOAD='(1.0,-1.0)';
      PINUSE='BI';
    'IO_L23P_T3_16':
      PIN_NUMBER='(0,0,E21,0,0)';
      OUTPUT_TYPE='(TS,TS)';
      BIDIRECTIONAL='TRUE';
      INPUT_LOAD='(-0.01,0.01)';
      OUTPUT_LOAD='(1.0,-1.0)';
      PINUSE='BI';
    'IO_L23P_T3_FOE_B_15':
      PIN_NUMBER='(0,0,L16,0,0)';
      OUTPUT_TYPE='(TS,TS)';
      BIDIRECTIONAL='TRUE';
      INPUT_LOAD='(-0.01,0.01)';
      OUTPUT_LOAD='(1.0,-1.0)';
      PINUSE='BI';
    'IO_L24N_T3_16':
      PIN_NUMBER='(0,0,G22,0,0)';
      OUTPUT_TYPE='(TS,TS)';
      BIDIRECTIONAL='TRUE';
      INPUT_LOAD='(-0.01,0.01)';
      OUTPUT_LOAD='(1.0,-1.0)';
      PINUSE='BI';
    'IO_L24N_T3_RS0_15':
      PIN_NUMBER='(0,0,M16,0,0)';
      OUTPUT_TYPE='(TS,TS)';
      BIDIRECTIONAL='TRUE';
      INPUT_LOAD='(-0.01,0.01)';
      OUTPUT_LOAD='(1.0,-1.0)';
      PINUSE='BI';
    'IO_L24P_T3_16':
      PIN_NUMBER='(0,0,G21,0,0)';
      OUTPUT_TYPE='(TS,TS)';
      BIDIRECTIONAL='TRUE';
      INPUT_LOAD='(-0.01,0.01)';
      OUTPUT_LOAD='(1.0,-1.0)';
      PINUSE='BI';
    'IO_L24P_T3_RS1_15':
      PIN_NUMBER='(0,0,M15,0,0)';
      OUTPUT_TYPE='(TS,TS)';
      BIDIRECTIONAL='TRUE';
      INPUT_LOAD='(-0.01,0.01)';
      OUTPUT_LOAD='(1.0,-1.0)';
      PINUSE='BI';
    'IO_0_34':
      PIN_NUMBER='(0,0,0,T3,0)';
      OUTPUT_TYPE='(TS,TS)';
      BIDIRECTIONAL='TRUE';
      INPUT_LOAD='(-0.01,0.01)';
      OUTPUT_LOAD='(1.0,-1.0)';
      PINUSE='BI';
    'IO_0_35':
      PIN_NUMBER='(0,0,0,F4,0)';
      OUTPUT_TYPE='(TS,TS)';
      BIDIRECTIONAL='TRUE';
      INPUT_LOAD='(-0.01,0.01)';
      OUTPUT_LOAD='(1.0,-1.0)';
      PINUSE='BI';
    'IO_25_34':
      PIN_NUMBER='(0,0,0,U7,0)';
      OUTPUT_TYPE='(TS,TS)';
      BIDIRECTIONAL='TRUE';
      INPUT_LOAD='(-0.01,0.01)';
      OUTPUT_LOAD='(1.0,-1.0)';
      PINUSE='BI';
    'IO_25_35':
      PIN_NUMBER='(0,0,0,L6,0)';
      OUTPUT_TYPE='(TS,TS)';
      BIDIRECTIONAL='TRUE';
      INPUT_LOAD='(-0.01,0.01)';
      OUTPUT_LOAD='(1.0,-1.0)';
      PINUSE='BI';
    'IO_L1N_T0_34':
      PIN_NUMBER='(0,0,0,U1,0)';
      OUTPUT_TYPE='(TS,TS)';
      BIDIRECTIONAL='TRUE';
      INPUT_LOAD='(-0.01,0.01)';
      OUTPUT_LOAD='(1.0,-1.0)';
      PINUSE='BI';
    'IO_L1N_T0_AD4N_35':
      PIN_NUMBER='(0,0,0,A1,0)';
      OUTPUT_TYPE='(TS,TS)';
      BIDIRECTIONAL='TRUE';
      INPUT_LOAD='(-0.01,0.01)';
      OUTPUT_LOAD='(1.0,-1.0)';
      PINUSE='BI';
    'IO_L1P_T0_34':
      PIN_NUMBER='(0,0,0,T1,0)';
      OUTPUT_TYPE='(TS,TS)';
      BIDIRECTIONAL='TRUE';
      INPUT_LOAD='(-0.01,0.01)';
      OUTPUT_LOAD='(1.0,-1.0)';
      PINUSE='BI';
    'IO_L1P_T0_AD4P_35':
      PIN_NUMBER='(0,0,0,B1,0)';
      OUTPUT_TYPE='(TS,TS)';
      BIDIRECTIONAL='TRUE';
      INPUT_LOAD='(-0.01,0.01)';
      OUTPUT_LOAD='(1.0,-1.0)';
      PINUSE='BI';
    'IO_L2N_T0_34':
      PIN_NUMBER='(0,0,0,V2,0)';
      OUTPUT_TYPE='(TS,TS)';
      BIDIRECTIONAL='TRUE';
      INPUT_LOAD='(-0.01,0.01)';
      OUTPUT_LOAD='(1.0,-1.0)';
      PINUSE='BI';
    'IO_L2N_T0_AD12N_35':
      PIN_NUMBER='(0,0,0,B2,0)';
      OUTPUT_TYPE='(TS,TS)';
      BIDIRECTIONAL='TRUE';
      INPUT_LOAD='(-0.01,0.01)';
      OUTPUT_LOAD='(1.0,-1.0)';
      PINUSE='BI';
    'IO_L2P_T0_34':
      PIN_NUMBER='(0,0,0,U2,0)';
      OUTPUT_TYPE='(TS,TS)';
      BIDIRECTIONAL='TRUE';
      INPUT_LOAD='(-0.01,0.01)';
      OUTPUT_LOAD='(1.0,-1.0)';
      PINUSE='BI';
    'IO_L2P_T0_AD12P_35':
      PIN_NUMBER='(0,0,0,C2,0)';
      OUTPUT_TYPE='(TS,TS)';
      BIDIRECTIONAL='TRUE';
      INPUT_LOAD='(-0.01,0.01)';
      OUTPUT_LOAD='(1.0,-1.0)';
      PINUSE='BI';
    'IO_L3N_T0_DQS_34':
      PIN_NUMBER='(0,0,0,R2,0)';
      OUTPUT_TYPE='(TS,TS)';
      BIDIRECTIONAL='TRUE';
      INPUT_LOAD='(-0.01,0.01)';
      OUTPUT_LOAD='(1.0,-1.0)';
      PINUSE='BI';
    'IO_L3N_T0_DQS_AD5N_35':
      PIN_NUMBER='(0,0,0,D1,0)';
      OUTPUT_TYPE='(TS,TS)';
      BIDIRECTIONAL='TRUE';
      INPUT_LOAD='(-0.01,0.01)';
      OUTPUT_LOAD='(1.0,-1.0)';
      PINUSE='BI';
    'IO_L3P_T0_DQS_34':
      PIN_NUMBER='(0,0,0,R3,0)';
      OUTPUT_TYPE='(TS,TS)';
      BIDIRECTIONAL='TRUE';
      INPUT_LOAD='(-0.01,0.01)';
      OUTPUT_LOAD='(1.0,-1.0)';
      PINUSE='BI';
    'IO_L3P_T0_DQS_AD5P_35':
      PIN_NUMBER='(0,0,0,E1,0)';
      OUTPUT_TYPE='(TS,TS)';
      BIDIRECTIONAL='TRUE';
      INPUT_LOAD='(-0.01,0.01)';
      OUTPUT_LOAD='(1.0,-1.0)';
      PINUSE='BI';
    'IO_L4N_T0_34':
      PIN_NUMBER='(0,0,0,Y2,0)';
      OUTPUT_TYPE='(TS,TS)';
      BIDIRECTIONAL='TRUE';
      INPUT_LOAD='(-0.01,0.01)';
      OUTPUT_LOAD='(1.0,-1.0)';
      PINUSE='BI';
    'IO_L4N_T0_35':
      PIN_NUMBER='(0,0,0,D2,0)';
      OUTPUT_TYPE='(TS,TS)';
      BIDIRECTIONAL='TRUE';
      INPUT_LOAD='(-0.01,0.01)';
      OUTPUT_LOAD='(1.0,-1.0)';
      PINUSE='BI';
    'IO_L4P_T0_34':
      PIN_NUMBER='(0,0,0,W2,0)';
      OUTPUT_TYPE='(TS,TS)';
      BIDIRECTIONAL='TRUE';
      INPUT_LOAD='(-0.01,0.01)';
      OUTPUT_LOAD='(1.0,-1.0)';
      PINUSE='BI';
    'IO_L4P_T0_35':
      PIN_NUMBER='(0,0,0,E2,0)';
      OUTPUT_TYPE='(TS,TS)';
      BIDIRECTIONAL='TRUE';
      INPUT_LOAD='(-0.01,0.01)';
      OUTPUT_LOAD='(1.0,-1.0)';
      PINUSE='BI';
    'IO_L5N_T0_34':
      PIN_NUMBER='(0,0,0,Y1,0)';
      OUTPUT_TYPE='(TS,TS)';
      BIDIRECTIONAL='TRUE';
      INPUT_LOAD='(-0.01,0.01)';
      OUTPUT_LOAD='(1.0,-1.0)';
      PINUSE='BI';
    'IO_L5N_T0_AD13N_35':
      PIN_NUMBER='(0,0,0,F1,0)';
      OUTPUT_TYPE='(TS,TS)';
      BIDIRECTIONAL='TRUE';
      INPUT_LOAD='(-0.01,0.01)';
      OUTPUT_LOAD='(1.0,-1.0)';
      PINUSE='BI';
    'IO_L5P_T0_34':
      PIN_NUMBER='(0,0,0,W1,0)';
      OUTPUT_TYPE='(TS,TS)';
      BIDIRECTIONAL='TRUE';
      INPUT_LOAD='(-0.01,0.01)';
      OUTPUT_LOAD='(1.0,-1.0)';
      PINUSE='BI';
    'IO_L5P_T0_AD13P_35':
      PIN_NUMBER='(0,0,0,G1,0)';
      OUTPUT_TYPE='(TS,TS)';
      BIDIRECTIONAL='TRUE';
      INPUT_LOAD='(-0.01,0.01)';
      OUTPUT_LOAD='(1.0,-1.0)';
      PINUSE='BI';
    'IO_L6N_T0_VREF_34':
      PIN_NUMBER='(0,0,0,V3,0)';
      OUTPUT_TYPE='(TS,TS)';
      BIDIRECTIONAL='TRUE';
      INPUT_LOAD='(-0.01,0.01)';
      OUTPUT_LOAD='(1.0,-1.0)';
      PINUSE='BI';
    'IO_L6N_T0_VREF_35':
      PIN_NUMBER='(0,0,0,E3,0)';
      OUTPUT_TYPE='(TS,TS)';
      BIDIRECTIONAL='TRUE';
      INPUT_LOAD='(-0.01,0.01)';
      OUTPUT_LOAD='(1.0,-1.0)';
      PINUSE='BI';
    'IO_L6P_T0_34':
      PIN_NUMBER='(0,0,0,U3,0)';
      OUTPUT_TYPE='(TS,TS)';
      BIDIRECTIONAL='TRUE';
      INPUT_LOAD='(-0.01,0.01)';
      OUTPUT_LOAD='(1.0,-1.0)';
      PINUSE='BI';
    'IO_L6P_T0_35':
      PIN_NUMBER='(0,0,0,F3,0)';
      OUTPUT_TYPE='(TS,TS)';
      BIDIRECTIONAL='TRUE';
      INPUT_LOAD='(-0.01,0.01)';
      OUTPUT_LOAD='(1.0,-1.0)';
      PINUSE='BI';
    'IO_L7N_T1_34':
      PIN_NUMBER='(0,0,0,AB1,0)';
      OUTPUT_TYPE='(TS,TS)';
      BIDIRECTIONAL='TRUE';
      INPUT_LOAD='(-0.01,0.01)';
      OUTPUT_LOAD='(1.0,-1.0)';
      PINUSE='BI';
    'IO_L7N_T1_AD6N_35':
      PIN_NUMBER='(0,0,0,J1,0)';
      OUTPUT_TYPE='(TS,TS)';
      BIDIRECTIONAL='TRUE';
      INPUT_LOAD='(-0.01,0.01)';
      OUTPUT_LOAD='(1.0,-1.0)';
      PINUSE='BI';
    'IO_L7P_T1_34':
      PIN_NUMBER='(0,0,0,AA1,0)';
      OUTPUT_TYPE='(TS,TS)';
      BIDIRECTIONAL='TRUE';
      INPUT_LOAD='(-0.01,0.01)';
      OUTPUT_LOAD='(1.0,-1.0)';
      PINUSE='BI';
    'IO_L7P_T1_AD6P_35':
      PIN_NUMBER='(0,0,0,K1,0)';
      OUTPUT_TYPE='(TS,TS)';
      BIDIRECTIONAL='TRUE';
      INPUT_LOAD='(-0.01,0.01)';
      OUTPUT_LOAD='(1.0,-1.0)';
      PINUSE='BI';
    'IO_L8N_T1_34':
      PIN_NUMBER='(0,0,0,AB2,0)';
      OUTPUT_TYPE='(TS,TS)';
      BIDIRECTIONAL='TRUE';
      INPUT_LOAD='(-0.01,0.01)';
      OUTPUT_LOAD='(1.0,-1.0)';
      PINUSE='BI';
    'IO_L8N_T1_AD14N_35':
      PIN_NUMBER='(0,0,0,G2,0)';
      OUTPUT_TYPE='(TS,TS)';
      BIDIRECTIONAL='TRUE';
      INPUT_LOAD='(-0.01,0.01)';
      OUTPUT_LOAD='(1.0,-1.0)';
      PINUSE='BI';
    'IO_L8P_T1_34':
      PIN_NUMBER='(0,0,0,AB3,0)';
      OUTPUT_TYPE='(TS,TS)';
      BIDIRECTIONAL='TRUE';
      INPUT_LOAD='(-0.01,0.01)';
      OUTPUT_LOAD='(1.0,-1.0)';
      PINUSE='BI';
    'IO_L8P_T1_AD14P_35':
      PIN_NUMBER='(0,0,0,H2,0)';
      OUTPUT_TYPE='(TS,TS)';
      BIDIRECTIONAL='TRUE';
      INPUT_LOAD='(-0.01,0.01)';
      OUTPUT_LOAD='(1.0,-1.0)';
      PINUSE='BI';
    'IO_L9N_T1_DQS_34':
      PIN_NUMBER='(0,0,0,AA3,0)';
      OUTPUT_TYPE='(TS,TS)';
      BIDIRECTIONAL='TRUE';
      INPUT_LOAD='(-0.01,0.01)';
      OUTPUT_LOAD='(1.0,-1.0)';
      PINUSE='BI';
    'IO_L9N_T1_DQS_AD7N_35':
      PIN_NUMBER='(0,0,0,J2,0)';
      OUTPUT_TYPE='(TS,TS)';
      BIDIRECTIONAL='TRUE';
      INPUT_LOAD='(-0.01,0.01)';
      OUTPUT_LOAD='(1.0,-1.0)';
      PINUSE='BI';
    'IO_L9P_T1_DQS_34':
      PIN_NUMBER='(0,0,0,Y3,0)';
      OUTPUT_TYPE='(TS,TS)';
      BIDIRECTIONAL='TRUE';
      INPUT_LOAD='(-0.01,0.01)';
      OUTPUT_LOAD='(1.0,-1.0)';
      PINUSE='BI';
    'IO_L9P_T1_DQS_AD7P_35':
      PIN_NUMBER='(0,0,0,K2,0)';
      OUTPUT_TYPE='(TS,TS)';
      BIDIRECTIONAL='TRUE';
      INPUT_LOAD='(-0.01,0.01)';
      OUTPUT_LOAD='(1.0,-1.0)';
      PINUSE='BI';
    'IO_L10N_T1_34':
      PIN_NUMBER='(0,0,0,AB5,0)';
      OUTPUT_TYPE='(TS,TS)';
      BIDIRECTIONAL='TRUE';
      INPUT_LOAD='(-0.01,0.01)';
      OUTPUT_LOAD='(1.0,-1.0)';
      PINUSE='BI';
    'IO_L10N_T1_AD15N_35':
      PIN_NUMBER='(0,0,0,H5,0)';
      OUTPUT_TYPE='(TS,TS)';
      BIDIRECTIONAL='TRUE';
      INPUT_LOAD='(-0.01,0.01)';
      OUTPUT_LOAD='(1.0,-1.0)';
      PINUSE='BI';
    'IO_L10P_T1_34':
      PIN_NUMBER='(0,0,0,AA5,0)';
      OUTPUT_TYPE='(TS,TS)';
      BIDIRECTIONAL='TRUE';
      INPUT_LOAD='(-0.01,0.01)';
      OUTPUT_LOAD='(1.0,-1.0)';
      PINUSE='BI';
    'IO_L10P_T1_AD15P_35':
      PIN_NUMBER='(0,0,0,J5,0)';
      OUTPUT_TYPE='(TS,TS)';
      BIDIRECTIONAL='TRUE';
      INPUT_LOAD='(-0.01,0.01)';
      OUTPUT_LOAD='(1.0,-1.0)';
      PINUSE='BI';
    'IO_L11N_T1_SRCC_34':
      PIN_NUMBER='(0,0,0,AA4,0)';
      OUTPUT_TYPE='(TS,TS)';
      BIDIRECTIONAL='TRUE';
      INPUT_LOAD='(-0.01,0.01)';
      OUTPUT_LOAD='(1.0,-1.0)';
      PINUSE='BI';
    'IO_L11N_T1_SRCC_35':
      PIN_NUMBER='(0,0,0,G3,0)';
      OUTPUT_TYPE='(TS,TS)';
      BIDIRECTIONAL='TRUE';
      INPUT_LOAD='(-0.01,0.01)';
      OUTPUT_LOAD='(1.0,-1.0)';
      PINUSE='BI';
    'IO_L11P_T1_SRCC_34':
      PIN_NUMBER='(0,0,0,Y4,0)';
      OUTPUT_TYPE='(TS,TS)';
      BIDIRECTIONAL='TRUE';
      INPUT_LOAD='(-0.01,0.01)';
      OUTPUT_LOAD='(1.0,-1.0)';
      PINUSE='BI';
    'IO_L11P_T1_SRCC_35':
      PIN_NUMBER='(0,0,0,H3,0)';
      OUTPUT_TYPE='(TS,TS)';
      BIDIRECTIONAL='TRUE';
      INPUT_LOAD='(-0.01,0.01)';
      OUTPUT_LOAD='(1.0,-1.0)';
      PINUSE='BI';
    'IO_L12N_T1_MRCC_34':
      PIN_NUMBER='(0,0,0,W4,0)';
      OUTPUT_TYPE='(TS,TS)';
      BIDIRECTIONAL='TRUE';
      INPUT_LOAD='(-0.01,0.01)';
      OUTPUT_LOAD='(1.0,-1.0)';
      PINUSE='BI';
    'IO_L12N_T1_MRCC_35':
      PIN_NUMBER='(0,0,0,G4,0)';
      OUTPUT_TYPE='(TS,TS)';
      BIDIRECTIONAL='TRUE';
      INPUT_LOAD='(-0.01,0.01)';
      OUTPUT_LOAD='(1.0,-1.0)';
      PINUSE='BI';
    'IO_L12P_T1_MRCC_34':
      PIN_NUMBER='(0,0,0,V4,0)';
      OUTPUT_TYPE='(TS,TS)';
      BIDIRECTIONAL='TRUE';
      INPUT_LOAD='(-0.01,0.01)';
      OUTPUT_LOAD='(1.0,-1.0)';
      PINUSE='BI';
    'IO_L12P_T1_MRCC_35':
      PIN_NUMBER='(0,0,0,H4,0)';
      OUTPUT_TYPE='(TS,TS)';
      BIDIRECTIONAL='TRUE';
      INPUT_LOAD='(-0.01,0.01)';
      OUTPUT_LOAD='(1.0,-1.0)';
      PINUSE='BI';
    'IO_L13N_T2_MRCC_34':
      PIN_NUMBER='(0,0,0,T4,0)';
      OUTPUT_TYPE='(TS,TS)';
      BIDIRECTIONAL='TRUE';
      INPUT_LOAD='(-0.01,0.01)';
      OUTPUT_LOAD='(1.0,-1.0)';
      PINUSE='BI';
    'IO_L13N_T2_MRCC_35':
      PIN_NUMBER='(0,0,0,J4,0)';
      OUTPUT_TYPE='(TS,TS)';
      BIDIRECTIONAL='TRUE';
      INPUT_LOAD='(-0.01,0.01)';
      OUTPUT_LOAD='(1.0,-1.0)';
      PINUSE='BI';
    'IO_L13P_T2_MRCC_34':
      PIN_NUMBER='(0,0,0,R4,0)';
      OUTPUT_TYPE='(TS,TS)';
      BIDIRECTIONAL='TRUE';
      INPUT_LOAD='(-0.01,0.01)';
      OUTPUT_LOAD='(1.0,-1.0)';
      PINUSE='BI';
    'IO_L13P_T2_MRCC_35':
      PIN_NUMBER='(0,0,0,K4,0)';
      OUTPUT_TYPE='(TS,TS)';
      BIDIRECTIONAL='TRUE';
      INPUT_LOAD='(-0.01,0.01)';
      OUTPUT_LOAD='(1.0,-1.0)';
      PINUSE='BI';
    'IO_L14N_T2_SRCC_34':
      PIN_NUMBER='(0,0,0,U5,0)';
      OUTPUT_TYPE='(TS,TS)';
      BIDIRECTIONAL='TRUE';
      INPUT_LOAD='(-0.01,0.01)';
      OUTPUT_LOAD='(1.0,-1.0)';
      PINUSE='BI';
    'IO_L14N_T2_SRCC_35':
      PIN_NUMBER='(0,0,0,K3,0)';
      OUTPUT_TYPE='(TS,TS)';
      BIDIRECTIONAL='TRUE';
      INPUT_LOAD='(-0.01,0.01)';
      OUTPUT_LOAD='(1.0,-1.0)';
      PINUSE='BI';
    'IO_L14P_T2_SRCC_34':
      PIN_NUMBER='(0,0,0,T5,0)';
      OUTPUT_TYPE='(TS,TS)';
      BIDIRECTIONAL='TRUE';
      INPUT_LOAD='(-0.01,0.01)';
      OUTPUT_LOAD='(1.0,-1.0)';
      PINUSE='BI';
    'IO_L14P_T2_SRCC_35':
      PIN_NUMBER='(0,0,0,L3,0)';
      OUTPUT_TYPE='(TS,TS)';
      BIDIRECTIONAL='TRUE';
      INPUT_LOAD='(-0.01,0.01)';
      OUTPUT_LOAD='(1.0,-1.0)';
      PINUSE='BI';
    'IO_L15N_T2_DQS_34':
      PIN_NUMBER='(0,0,0,W5,0)';
      OUTPUT_TYPE='(TS,TS)';
      BIDIRECTIONAL='TRUE';
      INPUT_LOAD='(-0.01,0.01)';
      OUTPUT_LOAD='(1.0,-1.0)';
      PINUSE='BI';
    'IO_L15N_T2_DQS_35':
      PIN_NUMBER='(0,0,0,L1,0)';
      OUTPUT_TYPE='(TS,TS)';
      BIDIRECTIONAL='TRUE';
      INPUT_LOAD='(-0.01,0.01)';
      OUTPUT_LOAD='(1.0,-1.0)';
      PINUSE='BI';
    'IO_L15P_T2_DQS_34':
      PIN_NUMBER='(0,0,0,W6,0)';
      OUTPUT_TYPE='(TS,TS)';
      BIDIRECTIONAL='TRUE';
      INPUT_LOAD='(-0.01,0.01)';
      OUTPUT_LOAD='(1.0,-1.0)';
      PINUSE='BI';
    'IO_L15P_T2_DQS_35':
      PIN_NUMBER='(0,0,0,M1,0)';
      OUTPUT_TYPE='(TS,TS)';
      BIDIRECTIONAL='TRUE';
      INPUT_LOAD='(-0.01,0.01)';
      OUTPUT_LOAD='(1.0,-1.0)';
      PINUSE='BI';
    'IO_L16N_T2_34':
      PIN_NUMBER='(0,0,0,V5,0)';
      OUTPUT_TYPE='(TS,TS)';
      BIDIRECTIONAL='TRUE';
      INPUT_LOAD='(-0.01,0.01)';
      OUTPUT_LOAD='(1.0,-1.0)';
      PINUSE='BI';
    'IO_L16N_T2_35':
      PIN_NUMBER='(0,0,0,M2,0)';
      OUTPUT_TYPE='(TS,TS)';
      BIDIRECTIONAL='TRUE';
      INPUT_LOAD='(-0.01,0.01)';
      OUTPUT_LOAD='(1.0,-1.0)';
      PINUSE='BI';
    'IO_L16P_T2_34':
      PIN_NUMBER='(0,0,0,U6,0)';
      OUTPUT_TYPE='(TS,TS)';
      BIDIRECTIONAL='TRUE';
      INPUT_LOAD='(-0.01,0.01)';
      OUTPUT_LOAD='(1.0,-1.0)';
      PINUSE='BI';
    'IO_L16P_T2_35':
      PIN_NUMBER='(0,0,0,M3,0)';
      OUTPUT_TYPE='(TS,TS)';
      BIDIRECTIONAL='TRUE';
      INPUT_LOAD='(-0.01,0.01)';
      OUTPUT_LOAD='(1.0,-1.0)';
      PINUSE='BI';
    'IO_L17N_T2_34':
      PIN_NUMBER='(0,0,0,T6,0)';
      OUTPUT_TYPE='(TS,TS)';
      BIDIRECTIONAL='TRUE';
      INPUT_LOAD='(-0.01,0.01)';
      OUTPUT_LOAD='(1.0,-1.0)';
      PINUSE='BI';
    'IO_L17N_T2_35':
      PIN_NUMBER='(0,0,0,J6,0)';
      OUTPUT_TYPE='(TS,TS)';
      BIDIRECTIONAL='TRUE';
      INPUT_LOAD='(-0.01,0.01)';
      OUTPUT_LOAD='(1.0,-1.0)';
      PINUSE='BI';
    'IO_L17P_T2_34':
      PIN_NUMBER='(0,0,0,R6,0)';
      OUTPUT_TYPE='(TS,TS)';
      BIDIRECTIONAL='TRUE';
      INPUT_LOAD='(-0.01,0.01)';
      OUTPUT_LOAD='(1.0,-1.0)';
      PINUSE='BI';
    'IO_L17P_T2_35':
      PIN_NUMBER='(0,0,0,K6,0)';
      OUTPUT_TYPE='(TS,TS)';
      BIDIRECTIONAL='TRUE';
      INPUT_LOAD='(-0.01,0.01)';
      OUTPUT_LOAD='(1.0,-1.0)';
      PINUSE='BI';
    'IO_L18N_T2_34':
      PIN_NUMBER='(0,0,0,AA6,0)';
      OUTPUT_TYPE='(TS,TS)';
      BIDIRECTIONAL='TRUE';
      INPUT_LOAD='(-0.01,0.01)';
      OUTPUT_LOAD='(1.0,-1.0)';
      PINUSE='BI';
    'IO_L18N_T2_35':
      PIN_NUMBER='(0,0,0,L4,0)';
      OUTPUT_TYPE='(TS,TS)';
      BIDIRECTIONAL='TRUE';
      INPUT_LOAD='(-0.01,0.01)';
      OUTPUT_LOAD='(1.0,-1.0)';
      PINUSE='BI';
    'IO_L18P_T2_34':
      PIN_NUMBER='(0,0,0,Y6,0)';
      OUTPUT_TYPE='(TS,TS)';
      BIDIRECTIONAL='TRUE';
      INPUT_LOAD='(-0.01,0.01)';
      OUTPUT_LOAD='(1.0,-1.0)';
      PINUSE='BI';
    'IO_L18P_T2_35':
      PIN_NUMBER='(0,0,0,L5,0)';
      OUTPUT_TYPE='(TS,TS)';
      BIDIRECTIONAL='TRUE';
      INPUT_LOAD='(-0.01,0.01)';
      OUTPUT_LOAD='(1.0,-1.0)';
      PINUSE='BI';
    'IO_L19N_T3_VREF_34':
      PIN_NUMBER='(0,0,0,W7,0)';
      OUTPUT_TYPE='(TS,TS)';
      BIDIRECTIONAL='TRUE';
      INPUT_LOAD='(-0.01,0.01)';
      OUTPUT_LOAD='(1.0,-1.0)';
      PINUSE='BI';
    'IO_L19N_T3_VREF_35':
      PIN_NUMBER='(0,0,0,N3,0)';
      OUTPUT_TYPE='(TS,TS)';
      BIDIRECTIONAL='TRUE';
      INPUT_LOAD='(-0.01,0.01)';
      OUTPUT_LOAD='(1.0,-1.0)';
      PINUSE='BI';
    'IO_L19P_T3_34':
      PIN_NUMBER='(0,0,0,V7,0)';
      OUTPUT_TYPE='(TS,TS)';
      BIDIRECTIONAL='TRUE';
      INPUT_LOAD='(-0.01,0.01)';
      OUTPUT_LOAD='(1.0,-1.0)';
      PINUSE='BI';
    'IO_L19P_T3_35':
      PIN_NUMBER='(0,0,0,N4,0)';
      OUTPUT_TYPE='(TS,TS)';
      BIDIRECTIONAL='TRUE';
      INPUT_LOAD='(-0.01,0.01)';
      OUTPUT_LOAD='(1.0,-1.0)';
      PINUSE='BI';
    'IO_L20N_T3_34':
      PIN_NUMBER='(0,0,0,AB6,0)';
      OUTPUT_TYPE='(TS,TS)';
      BIDIRECTIONAL='TRUE';
      INPUT_LOAD='(-0.01,0.01)';
      OUTPUT_LOAD='(1.0,-1.0)';
      PINUSE='BI';
    'IO_L20N_T3_35':
      PIN_NUMBER='(0,0,0,P1,0)';
      OUTPUT_TYPE='(TS,TS)';
      BIDIRECTIONAL='TRUE';
      INPUT_LOAD='(-0.01,0.01)';
      OUTPUT_LOAD='(1.0,-1.0)';
      PINUSE='BI';
    'IO_L20P_T3_34':
      PIN_NUMBER='(0,0,0,AB7,0)';
      OUTPUT_TYPE='(TS,TS)';
      BIDIRECTIONAL='TRUE';
      INPUT_LOAD='(-0.01,0.01)';
      OUTPUT_LOAD='(1.0,-1.0)';
      PINUSE='BI';
    'IO_L20P_T3_35':
      PIN_NUMBER='(0,0,0,R1,0)';
      OUTPUT_TYPE='(TS,TS)';
      BIDIRECTIONAL='TRUE';
      INPUT_LOAD='(-0.01,0.01)';
      OUTPUT_LOAD='(1.0,-1.0)';
      PINUSE='BI';
    'IO_L21N_T3_DQS_34':
      PIN_NUMBER='(0,0,0,V8,0)';
      OUTPUT_TYPE='(TS,TS)';
      BIDIRECTIONAL='TRUE';
      INPUT_LOAD='(-0.01,0.01)';
      OUTPUT_LOAD='(1.0,-1.0)';
      PINUSE='BI';
    'IO_L21N_T3_DQS_35':
      PIN_NUMBER='(0,0,0,P4,0)';
      OUTPUT_TYPE='(TS,TS)';
      BIDIRECTIONAL='TRUE';
      INPUT_LOAD='(-0.01,0.01)';
      OUTPUT_LOAD='(1.0,-1.0)';
      PINUSE='BI';
    'IO_L21P_T3_DQS_34':
      PIN_NUMBER='(0,0,0,V9,0)';
      OUTPUT_TYPE='(TS,TS)';
      BIDIRECTIONAL='TRUE';
      INPUT_LOAD='(-0.01,0.01)';
      OUTPUT_LOAD='(1.0,-1.0)';
      PINUSE='BI';
    'IO_L21P_T3_DQS_35':
      PIN_NUMBER='(0,0,0,P5,0)';
      OUTPUT_TYPE='(TS,TS)';
      BIDIRECTIONAL='TRUE';
      INPUT_LOAD='(-0.01,0.01)';
      OUTPUT_LOAD='(1.0,-1.0)';
      PINUSE='BI';
    'IO_L22N_T3_34':
      PIN_NUMBER='(0,0,0,AB8,0)';
      OUTPUT_TYPE='(TS,TS)';
      BIDIRECTIONAL='TRUE';
      INPUT_LOAD='(-0.01,0.01)';
      OUTPUT_LOAD='(1.0,-1.0)';
      PINUSE='BI';
    'IO_L22N_T3_35':
      PIN_NUMBER='(0,0,0,N2,0)';
      OUTPUT_TYPE='(TS,TS)';
      BIDIRECTIONAL='TRUE';
      INPUT_LOAD='(-0.01,0.01)';
      OUTPUT_LOAD='(1.0,-1.0)';
      PINUSE='BI';
    'IO_L22P_T3_34':
      PIN_NUMBER='(0,0,0,AA8,0)';
      OUTPUT_TYPE='(TS,TS)';
      BIDIRECTIONAL='TRUE';
      INPUT_LOAD='(-0.01,0.01)';
      OUTPUT_LOAD='(1.0,-1.0)';
      PINUSE='BI';
    'IO_L22P_T3_35':
      PIN_NUMBER='(0,0,0,P2,0)';
      OUTPUT_TYPE='(TS,TS)';
      BIDIRECTIONAL='TRUE';
      INPUT_LOAD='(-0.01,0.01)';
      OUTPUT_LOAD='(1.0,-1.0)';
      PINUSE='BI';
    'IO_L23N_T3_34':
      PIN_NUMBER='(0,0,0,Y7,0)';
      OUTPUT_TYPE='(TS,TS)';
      BIDIRECTIONAL='TRUE';
      INPUT_LOAD='(-0.01,0.01)';
      OUTPUT_LOAD='(1.0,-1.0)';
      PINUSE='BI';
    'IO_L23N_T3_35':
      PIN_NUMBER='(0,0,0,M5,0)';
      OUTPUT_TYPE='(TS,TS)';
      BIDIRECTIONAL='TRUE';
      INPUT_LOAD='(-0.01,0.01)';
      OUTPUT_LOAD='(1.0,-1.0)';
      PINUSE='BI';
    'IO_L23P_T3_34':
      PIN_NUMBER='(0,0,0,Y8,0)';
      OUTPUT_TYPE='(TS,TS)';
      BIDIRECTIONAL='TRUE';
      INPUT_LOAD='(-0.01,0.01)';
      OUTPUT_LOAD='(1.0,-1.0)';
      PINUSE='BI';
    'IO_L23P_T3_35':
      PIN_NUMBER='(0,0,0,M6,0)';
      OUTPUT_TYPE='(TS,TS)';
      BIDIRECTIONAL='TRUE';
      INPUT_LOAD='(-0.01,0.01)';
      OUTPUT_LOAD='(1.0,-1.0)';
      PINUSE='BI';
    'IO_L24N_T3_34':
      PIN_NUMBER='(0,0,0,Y9,0)';
      OUTPUT_TYPE='(TS,TS)';
      BIDIRECTIONAL='TRUE';
      INPUT_LOAD='(-0.01,0.01)';
      OUTPUT_LOAD='(1.0,-1.0)';
      PINUSE='BI';
    'IO_L24N_T3_35':
      PIN_NUMBER='(0,0,0,N5,0)';
      OUTPUT_TYPE='(TS,TS)';
      BIDIRECTIONAL='TRUE';
      INPUT_LOAD='(-0.01,0.01)';
      OUTPUT_LOAD='(1.0,-1.0)';
      PINUSE='BI';
    'IO_L24P_T3_34':
      PIN_NUMBER='(0,0,0,W9,0)';
      OUTPUT_TYPE='(TS,TS)';
      BIDIRECTIONAL='TRUE';
      INPUT_LOAD='(-0.01,0.01)';
      OUTPUT_LOAD='(1.0,-1.0)';
      PINUSE='BI';
    'IO_L24P_T3_35':
      PIN_NUMBER='(0,0,0,P6,0)';
      OUTPUT_TYPE='(TS,TS)';
      BIDIRECTIONAL='TRUE';
      INPUT_LOAD='(-0.01,0.01)';
      OUTPUT_LOAD='(1.0,-1.0)';
      PINUSE='BI';
    'GNDADC_0':
      PIN_NUMBER='(0,0,0,0,K9)';
      PINUSE='GROUND';
      NO_LOAD_CHECK='Both';
      NO_IO_CHECK='Both';
      NO_ASSERT_CHECK='TRUE';
      NO_DIR_CHECK='TRUE';
      ALLOW_CONNECT='TRUE';
    'GND_1':
      PIN_NUMBER='(0,0,0,0,A11)';
      PINUSE='GROUND';
      NO_LOAD_CHECK='Both';
      NO_IO_CHECK='Both';
      NO_ASSERT_CHECK='TRUE';
      NO_DIR_CHECK='TRUE';
      ALLOW_CONNECT='TRUE';
    'GND_2':
      PIN_NUMBER='(0,0,0,0,A12)';
      PINUSE='GROUND';
      NO_LOAD_CHECK='Both';
      NO_IO_CHECK='Both';
      NO_ASSERT_CHECK='TRUE';
      NO_DIR_CHECK='TRUE';
      ALLOW_CONNECT='TRUE';
    'GND_3':
      PIN_NUMBER='(0,0,0,0,A2)';
      PINUSE='GROUND';
      NO_LOAD_CHECK='Both';
      NO_IO_CHECK='Both';
      NO_ASSERT_CHECK='TRUE';
      NO_DIR_CHECK='TRUE';
      ALLOW_CONNECT='TRUE';
    'GND_4':
      PIN_NUMBER='(0,0,0,0,A22)';
      PINUSE='GROUND';
      NO_LOAD_CHECK='Both';
      NO_IO_CHECK='Both';
      NO_ASSERT_CHECK='TRUE';
      NO_DIR_CHECK='TRUE';
      ALLOW_CONNECT='TRUE';
    'GND_5':
      PIN_NUMBER='(0,0,0,0,A3)';
      PINUSE='GROUND';
      NO_LOAD_CHECK='Both';
      NO_IO_CHECK='Both';
      NO_ASSERT_CHECK='TRUE';
      NO_DIR_CHECK='TRUE';
      ALLOW_CONNECT='TRUE';
    'GND_6':
      PIN_NUMBER='(0,0,0,0,A5)';
      PINUSE='GROUND';
      NO_LOAD_CHECK='Both';
      NO_IO_CHECK='Both';
      NO_ASSERT_CHECK='TRUE';
      NO_DIR_CHECK='TRUE';
      ALLOW_CONNECT='TRUE';
    'GND_7':
      PIN_NUMBER='(0,0,0,0,A7)';
      PINUSE='GROUND';
      NO_LOAD_CHECK='Both';
      NO_IO_CHECK='Both';
      NO_ASSERT_CHECK='TRUE';
      NO_DIR_CHECK='TRUE';
      ALLOW_CONNECT='TRUE';
    'GND_8':
      PIN_NUMBER='(0,0,0,0,A9)';
      PINUSE='GROUND';
      NO_LOAD_CHECK='Both';
      NO_IO_CHECK='Both';
      NO_ASSERT_CHECK='TRUE';
      NO_DIR_CHECK='TRUE';
      ALLOW_CONNECT='TRUE';
    'GND_9':
      PIN_NUMBER='(0,0,0,0,AA12)';
      PINUSE='GROUND';
      NO_LOAD_CHECK='Both';
      NO_IO_CHECK='Both';
      NO_ASSERT_CHECK='TRUE';
      NO_DIR_CHECK='TRUE';
      ALLOW_CONNECT='TRUE';
    'GND_10':
      PIN_NUMBER='(0,0,0,0,AA2)';
      PINUSE='GROUND';
      NO_LOAD_CHECK='Both';
      NO_IO_CHECK='Both';
      NO_ASSERT_CHECK='TRUE';
      NO_DIR_CHECK='TRUE';
      ALLOW_CONNECT='TRUE';
    'GND_11':
      PIN_NUMBER='(0,0,0,0,AA22)';
      PINUSE='GROUND';
      NO_LOAD_CHECK='Both';
      NO_IO_CHECK='Both';
      NO_ASSERT_CHECK='TRUE';
      NO_DIR_CHECK='TRUE';
      ALLOW_CONNECT='TRUE';
    'GND_12':
      PIN_NUMBER='(0,0,0,0,AB19)';
      PINUSE='GROUND';
      NO_LOAD_CHECK='Both';
      NO_IO_CHECK='Both';
      NO_ASSERT_CHECK='TRUE';
      NO_DIR_CHECK='TRUE';
      ALLOW_CONNECT='TRUE';
    'GND_13':
      PIN_NUMBER='(0,0,0,0,AB9)';
      PINUSE='GROUND';
      NO_LOAD_CHECK='Both';
      NO_IO_CHECK='Both';
      NO_ASSERT_CHECK='TRUE';
      NO_DIR_CHECK='TRUE';
      ALLOW_CONNECT='TRUE';
    'GND_14':
      PIN_NUMBER='(0,0,0,0,B12)';
      PINUSE='GROUND';
      NO_LOAD_CHECK='Both';
      NO_IO_CHECK='Both';
      NO_ASSERT_CHECK='TRUE';
      NO_DIR_CHECK='TRUE';
      ALLOW_CONNECT='TRUE';
    'GND_15':
      PIN_NUMBER='(0,0,0,0,B19)';
      PINUSE='GROUND';
      NO_LOAD_CHECK='Both';
      NO_IO_CHECK='Both';
      NO_ASSERT_CHECK='TRUE';
      NO_DIR_CHECK='TRUE';
      ALLOW_CONNECT='TRUE';
    'GND_16':
      PIN_NUMBER='(0,0,0,0,B3)';
      PINUSE='GROUND';
      NO_LOAD_CHECK='Both';
      NO_IO_CHECK='Both';
      NO_ASSERT_CHECK='TRUE';
      NO_DIR_CHECK='TRUE';
      ALLOW_CONNECT='TRUE';
    'GND_17':
      PIN_NUMBER='(0,0,0,0,C10)';
      PINUSE='GROUND';
      NO_LOAD_CHECK='Both';
      NO_IO_CHECK='Both';
      NO_ASSERT_CHECK='TRUE';
      NO_DIR_CHECK='TRUE';
      ALLOW_CONNECT='TRUE';
    'GND_18':
      PIN_NUMBER='(0,0,0,0,C12)';
      PINUSE='GROUND';
      NO_LOAD_CHECK='Both';
      NO_IO_CHECK='Both';
      NO_ASSERT_CHECK='TRUE';
      NO_DIR_CHECK='TRUE';
      ALLOW_CONNECT='TRUE';
    'GND_19':
      PIN_NUMBER='(0,0,0,0,C16)';
      PINUSE='GROUND';
      NO_LOAD_CHECK='Both';
      NO_IO_CHECK='Both';
      NO_ASSERT_CHECK='TRUE';
      NO_DIR_CHECK='TRUE';
      ALLOW_CONNECT='TRUE';
    'GND_20':
      PIN_NUMBER='(0,0,0,0,C3)';
      PINUSE='GROUND';
      NO_LOAD_CHECK='Both';
      NO_IO_CHECK='Both';
      NO_ASSERT_CHECK='TRUE';
      NO_DIR_CHECK='TRUE';
      ALLOW_CONNECT='TRUE';
    'GND_21':
      PIN_NUMBER='(0,0,0,0,C6)';
      PINUSE='GROUND';
      NO_LOAD_CHECK='Both';
      NO_IO_CHECK='Both';
      NO_ASSERT_CHECK='TRUE';
      NO_DIR_CHECK='TRUE';
      ALLOW_CONNECT='TRUE';
    'GND_22':
      PIN_NUMBER='(0,0,0,0,D12)';
      PINUSE='GROUND';
      NO_LOAD_CHECK='Both';
      NO_IO_CHECK='Both';
      NO_ASSERT_CHECK='TRUE';
      NO_DIR_CHECK='TRUE';
      ALLOW_CONNECT='TRUE';
    'GND_23':
      PIN_NUMBER='(0,0,0,0,D13)';
      PINUSE='GROUND';
      NO_LOAD_CHECK='Both';
      NO_IO_CHECK='Both';
      NO_ASSERT_CHECK='TRUE';
      NO_DIR_CHECK='TRUE';
      ALLOW_CONNECT='TRUE';
    'GND_24':
      PIN_NUMBER='(0,0,0,0,D3)';
      PINUSE='GROUND';
      NO_LOAD_CHECK='Both';
      NO_IO_CHECK='Both';
      NO_ASSERT_CHECK='TRUE';
      NO_DIR_CHECK='TRUE';
      ALLOW_CONNECT='TRUE';
    'GND_25':
      PIN_NUMBER='(0,0,0,0,D4)';
      PINUSE='GROUND';
      NO_LOAD_CHECK='Both';
      NO_IO_CHECK='Both';
      NO_ASSERT_CHECK='TRUE';
      NO_DIR_CHECK='TRUE';
      ALLOW_CONNECT='TRUE';
    'GND_26':
      PIN_NUMBER='(0,0,0,0,D8)';
      PINUSE='GROUND';
      NO_LOAD_CHECK='Both';
      NO_IO_CHECK='Both';
      NO_ASSERT_CHECK='TRUE';
      NO_DIR_CHECK='TRUE';
      ALLOW_CONNECT='TRUE';
    'GND_27':
      PIN_NUMBER='(0,0,0,0,E11)';
      PINUSE='GROUND';
      NO_LOAD_CHECK='Both';
      NO_IO_CHECK='Both';
      NO_ASSERT_CHECK='TRUE';
      NO_DIR_CHECK='TRUE';
      ALLOW_CONNECT='TRUE';
    'GND_28':
      PIN_NUMBER='(0,0,0,0,E20)';
      PINUSE='GROUND';
      NO_LOAD_CHECK='Both';
      NO_IO_CHECK='Both';
      NO_ASSERT_CHECK='TRUE';
      NO_DIR_CHECK='TRUE';
      ALLOW_CONNECT='TRUE';
    'GND_29':
      PIN_NUMBER='(0,0,0,0,E4)';
      PINUSE='GROUND';
      NO_LOAD_CHECK='Both';
      NO_IO_CHECK='Both';
      NO_ASSERT_CHECK='TRUE';
      NO_DIR_CHECK='TRUE';
      ALLOW_CONNECT='TRUE';
    'GND_30':
      PIN_NUMBER='(0,0,0,0,E5)';
      PINUSE='GROUND';
      NO_LOAD_CHECK='Both';
      NO_IO_CHECK='Both';
      NO_ASSERT_CHECK='TRUE';
      NO_DIR_CHECK='TRUE';
      ALLOW_CONNECT='TRUE';
    'GND_31':
      PIN_NUMBER='(0,0,0,0,E7)';
      PINUSE='GROUND';
      NO_LOAD_CHECK='Both';
      NO_IO_CHECK='Both';
      NO_ASSERT_CHECK='TRUE';
      NO_DIR_CHECK='TRUE';
      ALLOW_CONNECT='TRUE';
    'GND_32':
      PIN_NUMBER='(0,0,0,0,E9)';
      PINUSE='GROUND';
      NO_LOAD_CHECK='Both';
      NO_IO_CHECK='Both';
      NO_ASSERT_CHECK='TRUE';
      NO_DIR_CHECK='TRUE';
      ALLOW_CONNECT='TRUE';
    'GND_33':
      PIN_NUMBER='(0,0,0,0,F11)';
      PINUSE='GROUND';
      NO_LOAD_CHECK='Both';
      NO_IO_CHECK='Both';
      NO_ASSERT_CHECK='TRUE';
      NO_DIR_CHECK='TRUE';
      ALLOW_CONNECT='TRUE';
    'GND_34':
      PIN_NUMBER='(0,0,0,0,F17)';
      PINUSE='GROUND';
      NO_LOAD_CHECK='Both';
      NO_IO_CHECK='Both';
      NO_ASSERT_CHECK='TRUE';
      NO_DIR_CHECK='TRUE';
      ALLOW_CONNECT='TRUE';
    'GND_35':
      PIN_NUMBER='(0,0,0,0,F5)';
      PINUSE='GROUND';
      NO_LOAD_CHECK='Both';
      NO_IO_CHECK='Both';
      NO_ASSERT_CHECK='TRUE';
      NO_DIR_CHECK='TRUE';
      ALLOW_CONNECT='TRUE';
    'GND_36':
      PIN_NUMBER='(0,0,0,0,G10)';
      PINUSE='GROUND';
      NO_LOAD_CHECK='Both';
      NO_IO_CHECK='Both';
      NO_ASSERT_CHECK='TRUE';
      NO_DIR_CHECK='TRUE';
      ALLOW_CONNECT='TRUE';
    'GND_37':
      PIN_NUMBER='(0,0,0,0,G12)';
      PINUSE='GROUND';
      NO_LOAD_CHECK='Both';
      NO_IO_CHECK='Both';
      NO_ASSERT_CHECK='TRUE';
      NO_DIR_CHECK='TRUE';
      ALLOW_CONNECT='TRUE';
    'GND_38':
      PIN_NUMBER='(0,0,0,0,G14)';
      PINUSE='GROUND';
      NO_LOAD_CHECK='Both';
      NO_IO_CHECK='Both';
      NO_ASSERT_CHECK='TRUE';
      NO_DIR_CHECK='TRUE';
      ALLOW_CONNECT='TRUE';
    'GND_39':
      PIN_NUMBER='(0,0,0,0,G5)';
      PINUSE='GROUND';
      NO_LOAD_CHECK='Both';
      NO_IO_CHECK='Both';
      NO_ASSERT_CHECK='TRUE';
      NO_DIR_CHECK='TRUE';
      ALLOW_CONNECT='TRUE';
    'GND_40':
      PIN_NUMBER='(0,0,0,0,G6)';
      PINUSE='GROUND';
      NO_LOAD_CHECK='Both';
      NO_IO_CHECK='Both';
      NO_ASSERT_CHECK='TRUE';
      NO_DIR_CHECK='TRUE';
      ALLOW_CONNECT='TRUE';
    'GND_41':
      PIN_NUMBER='(0,0,0,0,G7)';
      PINUSE='GROUND';
      NO_LOAD_CHECK='Both';
      NO_IO_CHECK='Both';
      NO_ASSERT_CHECK='TRUE';
      NO_DIR_CHECK='TRUE';
      ALLOW_CONNECT='TRUE';
    'GND_42':
      PIN_NUMBER='(0,0,0,0,G8)';
      PINUSE='GROUND';
      NO_LOAD_CHECK='Both';
      NO_IO_CHECK='Both';
      NO_ASSERT_CHECK='TRUE';
      NO_DIR_CHECK='TRUE';
      ALLOW_CONNECT='TRUE';
    'GND_43':
      PIN_NUMBER='(0,0,0,0,G9)';
      PINUSE='GROUND';
      NO_LOAD_CHECK='Both';
      NO_IO_CHECK='Both';
      NO_ASSERT_CHECK='TRUE';
      NO_DIR_CHECK='TRUE';
      ALLOW_CONNECT='TRUE';
    'GND_44':
      PIN_NUMBER='(0,0,0,0,H1)';
      PINUSE='GROUND';
      NO_LOAD_CHECK='Both';
      NO_IO_CHECK='Both';
      NO_ASSERT_CHECK='TRUE';
      NO_DIR_CHECK='TRUE';
      ALLOW_CONNECT='TRUE';
    'GND_45':
      PIN_NUMBER='(0,0,0,0,H11)';
      PINUSE='GROUND';
      NO_LOAD_CHECK='Both';
      NO_IO_CHECK='Both';
      NO_ASSERT_CHECK='TRUE';
      NO_DIR_CHECK='TRUE';
      ALLOW_CONNECT='TRUE';
    'GND_46':
      PIN_NUMBER='(0,0,0,0,H21)';
      PINUSE='GROUND';
      NO_LOAD_CHECK='Both';
      NO_IO_CHECK='Both';
      NO_ASSERT_CHECK='TRUE';
      NO_DIR_CHECK='TRUE';
      ALLOW_CONNECT='TRUE';
    'GND_47':
      PIN_NUMBER='(0,0,0,0,H7)';
      PINUSE='GROUND';
      NO_LOAD_CHECK='Both';
      NO_IO_CHECK='Both';
      NO_ASSERT_CHECK='TRUE';
      NO_DIR_CHECK='TRUE';
      ALLOW_CONNECT='TRUE';
    'GND_48':
      PIN_NUMBER='(0,0,0,0,H9)';
      PINUSE='GROUND';
      NO_LOAD_CHECK='Both';
      NO_IO_CHECK='Both';
      NO_ASSERT_CHECK='TRUE';
      NO_DIR_CHECK='TRUE';
      ALLOW_CONNECT='TRUE';
    'GND_49':
      PIN_NUMBER='(0,0,0,0,J10)';
      PINUSE='GROUND';
      NO_LOAD_CHECK='Both';
      NO_IO_CHECK='Both';
      NO_ASSERT_CHECK='TRUE';
      NO_DIR_CHECK='TRUE';
      ALLOW_CONNECT='TRUE';
    'GND_50':
      PIN_NUMBER='(0,0,0,0,J12)';
      PINUSE='GROUND';
      NO_LOAD_CHECK='Both';
      NO_IO_CHECK='Both';
      NO_ASSERT_CHECK='TRUE';
      NO_DIR_CHECK='TRUE';
      ALLOW_CONNECT='TRUE';
    'GND_51':
      PIN_NUMBER='(0,0,0,0,J18)';
      PINUSE='GROUND';
      NO_LOAD_CHECK='Both';
      NO_IO_CHECK='Both';
      NO_ASSERT_CHECK='TRUE';
      NO_DIR_CHECK='TRUE';
      ALLOW_CONNECT='TRUE';
    'GND_52':
      PIN_NUMBER='(0,0,0,0,J8)';
      PINUSE='GROUND';
      NO_LOAD_CHECK='Both';
      NO_IO_CHECK='Both';
      NO_ASSERT_CHECK='TRUE';
      NO_DIR_CHECK='TRUE';
      ALLOW_CONNECT='TRUE';
    'GND_53':
      PIN_NUMBER='(0,0,0,0,K11)';
      PINUSE='GROUND';
      NO_LOAD_CHECK='Both';
      NO_IO_CHECK='Both';
      NO_ASSERT_CHECK='TRUE';
      NO_DIR_CHECK='TRUE';
      ALLOW_CONNECT='TRUE';
    'GND_54':
      PIN_NUMBER='(0,0,0,0,K15)';
      PINUSE='GROUND';
      NO_LOAD_CHECK='Both';
      NO_IO_CHECK='Both';
      NO_ASSERT_CHECK='TRUE';
      NO_DIR_CHECK='TRUE';
      ALLOW_CONNECT='TRUE';
    'GND_55':
      PIN_NUMBER='(0,0,0,0,K5)';
      PINUSE='GROUND';
      NO_LOAD_CHECK='Both';
      NO_IO_CHECK='Both';
      NO_ASSERT_CHECK='TRUE';
      NO_DIR_CHECK='TRUE';
      ALLOW_CONNECT='TRUE';
    'GND_56':
      PIN_NUMBER='(0,0,0,0,K7)';
      PINUSE='GROUND';
      NO_LOAD_CHECK='Both';
      NO_IO_CHECK='Both';
      NO_ASSERT_CHECK='TRUE';
      NO_DIR_CHECK='TRUE';
      ALLOW_CONNECT='TRUE';
    'GND_57':
      PIN_NUMBER='(0,0,0,0,L2)';
      PINUSE='GROUND';
      NO_LOAD_CHECK='Both';
      NO_IO_CHECK='Both';
      NO_ASSERT_CHECK='TRUE';
      NO_DIR_CHECK='TRUE';
      ALLOW_CONNECT='TRUE';
    'GND_58':
      PIN_NUMBER='(0,0,0,0,L22)';
      PINUSE='GROUND';
      NO_LOAD_CHECK='Both';
      NO_IO_CHECK='Both';
      NO_ASSERT_CHECK='TRUE';
      NO_DIR_CHECK='TRUE';
      ALLOW_CONNECT='TRUE';
    'GND_59':
      PIN_NUMBER='(0,0,0,0,L8)';
      PINUSE='GROUND';
      NO_LOAD_CHECK='Both';
      NO_IO_CHECK='Both';
      NO_ASSERT_CHECK='TRUE';
      NO_DIR_CHECK='TRUE';
      ALLOW_CONNECT='TRUE';
    'GND_60':
      PIN_NUMBER='(0,0,0,0,M11)';
      PINUSE='GROUND';
      NO_LOAD_CHECK='Both';
      NO_IO_CHECK='Both';
      NO_ASSERT_CHECK='TRUE';
      NO_DIR_CHECK='TRUE';
      ALLOW_CONNECT='TRUE';
    'GND_61':
      PIN_NUMBER='(0,0,0,0,M19)';
      PINUSE='GROUND';
      NO_LOAD_CHECK='Both';
      NO_IO_CHECK='Both';
      NO_ASSERT_CHECK='TRUE';
      NO_DIR_CHECK='TRUE';
      ALLOW_CONNECT='TRUE';
    'GND_62':
      PIN_NUMBER='(0,0,0,0,M7)';
      PINUSE='GROUND';
      NO_LOAD_CHECK='Both';
      NO_IO_CHECK='Both';
      NO_ASSERT_CHECK='TRUE';
      NO_DIR_CHECK='TRUE';
      ALLOW_CONNECT='TRUE';
    'GND_63':
      PIN_NUMBER='(0,0,0,0,N16)';
      PINUSE='GROUND';
      NO_LOAD_CHECK='Both';
      NO_IO_CHECK='Both';
      NO_ASSERT_CHECK='TRUE';
      NO_DIR_CHECK='TRUE';
      ALLOW_CONNECT='TRUE';
    'GND_64':
      PIN_NUMBER='(0,0,0,0,N6)';
      PINUSE='GROUND';
      NO_LOAD_CHECK='Both';
      NO_IO_CHECK='Both';
      NO_ASSERT_CHECK='TRUE';
      NO_DIR_CHECK='TRUE';
      ALLOW_CONNECT='TRUE';
    'GND_65':
      PIN_NUMBER='(0,0,0,0,N8)';
      PINUSE='GROUND';
      NO_LOAD_CHECK='Both';
      NO_IO_CHECK='Both';
      NO_ASSERT_CHECK='TRUE';
      NO_DIR_CHECK='TRUE';
      ALLOW_CONNECT='TRUE';
    'GND_66':
      PIN_NUMBER='(0,0,0,0,P11)';
      PINUSE='GROUND';
      NO_LOAD_CHECK='Both';
      NO_IO_CHECK='Both';
      NO_ASSERT_CHECK='TRUE';
      NO_DIR_CHECK='TRUE';
      ALLOW_CONNECT='TRUE';
    'GND_67':
      PIN_NUMBER='(0,0,0,0,P13)';
      PINUSE='GROUND';
      NO_LOAD_CHECK='Both';
      NO_IO_CHECK='Both';
      NO_ASSERT_CHECK='TRUE';
      NO_DIR_CHECK='TRUE';
      ALLOW_CONNECT='TRUE';
    'GND_68':
      PIN_NUMBER='(0,0,0,0,P3)';
      PINUSE='GROUND';
      NO_LOAD_CHECK='Both';
      NO_IO_CHECK='Both';
      NO_ASSERT_CHECK='TRUE';
      NO_DIR_CHECK='TRUE';
      ALLOW_CONNECT='TRUE';
    'GND_69':
      PIN_NUMBER='(0,0,0,0,P7)';
      PINUSE='GROUND';
      NO_LOAD_CHECK='Both';
      NO_IO_CHECK='Both';
      NO_ASSERT_CHECK='TRUE';
      NO_DIR_CHECK='TRUE';
      ALLOW_CONNECT='TRUE';
    'GND_70':
      PIN_NUMBER='(0,0,0,0,P9)';
      PINUSE='GROUND';
      NO_LOAD_CHECK='Both';
      NO_IO_CHECK='Both';
      NO_ASSERT_CHECK='TRUE';
      NO_DIR_CHECK='TRUE';
      ALLOW_CONNECT='TRUE';
    'GND_71':
      PIN_NUMBER='(0,0,0,0,R10)';
      PINUSE='GROUND';
      NO_LOAD_CHECK='Both';
      NO_IO_CHECK='Both';
      NO_ASSERT_CHECK='TRUE';
      NO_DIR_CHECK='TRUE';
      ALLOW_CONNECT='TRUE';
    'GND_72':
      PIN_NUMBER='(0,0,0,0,R12)';
      PINUSE='GROUND';
      NO_LOAD_CHECK='Both';
      NO_IO_CHECK='Both';
      NO_ASSERT_CHECK='TRUE';
      NO_DIR_CHECK='TRUE';
      ALLOW_CONNECT='TRUE';
    'GND_73':
      PIN_NUMBER='(0,0,0,0,R20)';
      PINUSE='GROUND';
      NO_LOAD_CHECK='Both';
      NO_IO_CHECK='Both';
      NO_ASSERT_CHECK='TRUE';
      NO_DIR_CHECK='TRUE';
      ALLOW_CONNECT='TRUE';
    'GND_74':
      PIN_NUMBER='(0,0,0,0,R8)';
      PINUSE='GROUND';
      NO_LOAD_CHECK='Both';
      NO_IO_CHECK='Both';
      NO_ASSERT_CHECK='TRUE';
      NO_DIR_CHECK='TRUE';
      ALLOW_CONNECT='TRUE';
    'GND_75':
      PIN_NUMBER='(0,0,0,0,T11)';
      PINUSE='GROUND';
      NO_LOAD_CHECK='Both';
      NO_IO_CHECK='Both';
      NO_ASSERT_CHECK='TRUE';
      NO_DIR_CHECK='TRUE';
      ALLOW_CONNECT='TRUE';
    'GND_76':
      PIN_NUMBER='(0,0,0,0,T17)';
      PINUSE='GROUND';
      NO_LOAD_CHECK='Both';
      NO_IO_CHECK='Both';
      NO_ASSERT_CHECK='TRUE';
      NO_DIR_CHECK='TRUE';
      ALLOW_CONNECT='TRUE';
    'GND_77':
      PIN_NUMBER='(0,0,0,0,T7)';
      PINUSE='GROUND';
      NO_LOAD_CHECK='Both';
      NO_IO_CHECK='Both';
      NO_ASSERT_CHECK='TRUE';
      NO_DIR_CHECK='TRUE';
      ALLOW_CONNECT='TRUE';
    'GND_78':
      PIN_NUMBER='(0,0,0,0,T9)';
      PINUSE='GROUND';
      NO_LOAD_CHECK='Both';
      NO_IO_CHECK='Both';
      NO_ASSERT_CHECK='TRUE';
      NO_DIR_CHECK='TRUE';
      ALLOW_CONNECT='TRUE';
    'GND_79':
      PIN_NUMBER='(0,0,0,0,U14)';
      PINUSE='GROUND';
      NO_LOAD_CHECK='Both';
      NO_IO_CHECK='Both';
      NO_ASSERT_CHECK='TRUE';
      NO_DIR_CHECK='TRUE';
      ALLOW_CONNECT='TRUE';
    'GND_80':
      PIN_NUMBER='(0,0,0,0,U4)';
      PINUSE='GROUND';
      NO_LOAD_CHECK='Both';
      NO_IO_CHECK='Both';
      NO_ASSERT_CHECK='TRUE';
      NO_DIR_CHECK='TRUE';
      ALLOW_CONNECT='TRUE';
    'GND_81':
      PIN_NUMBER='(0,0,0,0,V1)';
      PINUSE='GROUND';
      NO_LOAD_CHECK='Both';
      NO_IO_CHECK='Both';
      NO_ASSERT_CHECK='TRUE';
      NO_DIR_CHECK='TRUE';
      ALLOW_CONNECT='TRUE';
    'GND_82':
      PIN_NUMBER='(0,0,0,0,V11)';
      PINUSE='GROUND';
      NO_LOAD_CHECK='Both';
      NO_IO_CHECK='Both';
      NO_ASSERT_CHECK='TRUE';
      NO_DIR_CHECK='TRUE';
      ALLOW_CONNECT='TRUE';
    'GND_83':
      PIN_NUMBER='(0,0,0,0,V21)';
      PINUSE='GROUND';
      NO_LOAD_CHECK='Both';
      NO_IO_CHECK='Both';
      NO_ASSERT_CHECK='TRUE';
      NO_DIR_CHECK='TRUE';
      ALLOW_CONNECT='TRUE';
    'GND_84':
      PIN_NUMBER='(0,0,0,0,W18)';
      PINUSE='GROUND';
      NO_LOAD_CHECK='Both';
      NO_IO_CHECK='Both';
      NO_ASSERT_CHECK='TRUE';
      NO_DIR_CHECK='TRUE';
      ALLOW_CONNECT='TRUE';
    'GND_85':
      PIN_NUMBER='(0,0,0,0,W8)';
      PINUSE='GROUND';
      NO_LOAD_CHECK='Both';
      NO_IO_CHECK='Both';
      NO_ASSERT_CHECK='TRUE';
      NO_DIR_CHECK='TRUE';
      ALLOW_CONNECT='TRUE';
    'GND_86':
      PIN_NUMBER='(0,0,0,0,Y15)';
      PINUSE='GROUND';
      NO_LOAD_CHECK='Both';
      NO_IO_CHECK='Both';
      NO_ASSERT_CHECK='TRUE';
      NO_DIR_CHECK='TRUE';
      ALLOW_CONNECT='TRUE';
    'GND_87':
      PIN_NUMBER='(0,0,0,0,Y5)';
      PINUSE='GROUND';
      NO_LOAD_CHECK='Both';
      NO_IO_CHECK='Both';
      NO_ASSERT_CHECK='TRUE';
      NO_DIR_CHECK='TRUE';
      ALLOW_CONNECT='TRUE';
    'MGTAVCC_1':
      PIN_NUMBER='(0,0,0,0,D10)';
      PINUSE='POWER';
      NO_LOAD_CHECK='Both';
      NO_IO_CHECK='Both';
      NO_ASSERT_CHECK='TRUE';
      NO_DIR_CHECK='TRUE';
      ALLOW_CONNECT='TRUE';
    'MGTAVCC_2':
      PIN_NUMBER='(0,0,0,0,D6)';
      PINUSE='POWER';
      NO_LOAD_CHECK='Both';
      NO_IO_CHECK='Both';
      NO_ASSERT_CHECK='TRUE';
      NO_DIR_CHECK='TRUE';
      ALLOW_CONNECT='TRUE';
    'MGTAVCC_3':
      PIN_NUMBER='(0,0,0,0,E8)';
      PINUSE='POWER';
      NO_LOAD_CHECK='Both';
      NO_IO_CHECK='Both';
      NO_ASSERT_CHECK='TRUE';
      NO_DIR_CHECK='TRUE';
      ALLOW_CONNECT='TRUE';
    'MGTAVCC_4':
      PIN_NUMBER='(0,0,0,0,F7)';
      PINUSE='POWER';
      NO_LOAD_CHECK='Both';
      NO_IO_CHECK='Both';
      NO_ASSERT_CHECK='TRUE';
      NO_DIR_CHECK='TRUE';
      ALLOW_CONNECT='TRUE';
    'MGTAVCC_5':
      PIN_NUMBER='(0,0,0,0,F9)';
      PINUSE='POWER';
      NO_LOAD_CHECK='Both';
      NO_IO_CHECK='Both';
      NO_ASSERT_CHECK='TRUE';
      NO_DIR_CHECK='TRUE';
      ALLOW_CONNECT='TRUE';
    'MGTAVTT_1':
      PIN_NUMBER='(0,0,0,0,B11)';
      PINUSE='POWER';
      NO_LOAD_CHECK='Both';
      NO_IO_CHECK='Both';
      NO_ASSERT_CHECK='TRUE';
      NO_DIR_CHECK='TRUE';
      ALLOW_CONNECT='TRUE';
    'MGTAVTT_2':
      PIN_NUMBER='(0,0,0,0,B5)';
      PINUSE='POWER';
      NO_LOAD_CHECK='Both';
      NO_IO_CHECK='Both';
      NO_ASSERT_CHECK='TRUE';
      NO_DIR_CHECK='TRUE';
      ALLOW_CONNECT='TRUE';
    'MGTAVTT_3':
      PIN_NUMBER='(0,0,0,0,B7)';
      PINUSE='POWER';
      NO_LOAD_CHECK='Both';
      NO_IO_CHECK='Both';
      NO_ASSERT_CHECK='TRUE';
      NO_DIR_CHECK='TRUE';
      ALLOW_CONNECT='TRUE';
    'MGTAVTT_4':
      PIN_NUMBER='(0,0,0,0,B9)';
      PINUSE='POWER';
      NO_LOAD_CHECK='Both';
      NO_IO_CHECK='Both';
      NO_ASSERT_CHECK='TRUE';
      NO_DIR_CHECK='TRUE';
      ALLOW_CONNECT='TRUE';
    'MGTAVTT_5':
      PIN_NUMBER='(0,0,0,0,C4)';
      PINUSE='POWER';
      NO_LOAD_CHECK='Both';
      NO_IO_CHECK='Both';
      NO_ASSERT_CHECK='TRUE';
      NO_DIR_CHECK='TRUE';
      ALLOW_CONNECT='TRUE';
    'MGTAVTT_6':
      PIN_NUMBER='(0,0,0,0,C8)';
      PINUSE='POWER';
      NO_LOAD_CHECK='Both';
      NO_IO_CHECK='Both';
      NO_ASSERT_CHECK='TRUE';
      NO_DIR_CHECK='TRUE';
      ALLOW_CONNECT='TRUE';
    'VCCADC_0':
      PIN_NUMBER='(0,0,0,0,K10)';
      PINUSE='POWER';
      NO_LOAD_CHECK='Both';
      NO_IO_CHECK='Both';
      NO_ASSERT_CHECK='TRUE';
      NO_DIR_CHECK='TRUE';
      ALLOW_CONNECT='TRUE';
    'VCCAUX_1':
      PIN_NUMBER='(0,0,0,0,H12)';
      PINUSE='POWER';
      NO_LOAD_CHECK='Both';
      NO_IO_CHECK='Both';
      NO_ASSERT_CHECK='TRUE';
      NO_DIR_CHECK='TRUE';
      ALLOW_CONNECT='TRUE';
    'VCCAUX_2':
      PIN_NUMBER='(0,0,0,0,K12)';
      PINUSE='POWER';
      NO_LOAD_CHECK='Both';
      NO_IO_CHECK='Both';
      NO_ASSERT_CHECK='TRUE';
      NO_DIR_CHECK='TRUE';
      ALLOW_CONNECT='TRUE';
    'VCCAUX_3':
      PIN_NUMBER='(0,0,0,0,M12)';
      PINUSE='POWER';
      NO_LOAD_CHECK='Both';
      NO_IO_CHECK='Both';
      NO_ASSERT_CHECK='TRUE';
      NO_DIR_CHECK='TRUE';
      ALLOW_CONNECT='TRUE';
    'VCCAUX_4':
      PIN_NUMBER='(0,0,0,0,P12)';
      PINUSE='POWER';
      NO_LOAD_CHECK='Both';
      NO_IO_CHECK='Both';
      NO_ASSERT_CHECK='TRUE';
      NO_DIR_CHECK='TRUE';
      ALLOW_CONNECT='TRUE';
    'VCCAUX_5':
      PIN_NUMBER='(0,0,0,0,R11)';
      PINUSE='POWER';
      NO_LOAD_CHECK='Both';
      NO_IO_CHECK='Both';
      NO_ASSERT_CHECK='TRUE';
      NO_DIR_CHECK='TRUE';
      ALLOW_CONNECT='TRUE';
    'VCCBATT_0':
      PIN_NUMBER='(0,0,0,0,E12)';
      PINUSE='POWER';
      NO_LOAD_CHECK='Both';
      NO_IO_CHECK='Both';
      NO_ASSERT_CHECK='TRUE';
      NO_DIR_CHECK='TRUE';
      ALLOW_CONNECT='TRUE';
    'VCCBRAM_1':
      PIN_NUMBER='(0,0,0,0,J11)';
      PINUSE='POWER';
      NO_LOAD_CHECK='Both';
      NO_IO_CHECK='Both';
      NO_ASSERT_CHECK='TRUE';
      NO_DIR_CHECK='TRUE';
      ALLOW_CONNECT='TRUE';
    'VCCBRAM_2':
      PIN_NUMBER='(0,0,0,0,L11)';
      PINUSE='POWER';
      NO_LOAD_CHECK='Both';
      NO_IO_CHECK='Both';
      NO_ASSERT_CHECK='TRUE';
      NO_DIR_CHECK='TRUE';
      ALLOW_CONNECT='TRUE';
    'VCCBRAM_3':
      PIN_NUMBER='(0,0,0,0,N11)';
      PINUSE='POWER';
      NO_LOAD_CHECK='Both';
      NO_IO_CHECK='Both';
      NO_ASSERT_CHECK='TRUE';
      NO_DIR_CHECK='TRUE';
      ALLOW_CONNECT='TRUE';
    'VCCINT_1':
      PIN_NUMBER='(0,0,0,0,H10)';
      PINUSE='POWER';
      NO_LOAD_CHECK='Both';
      NO_IO_CHECK='Both';
      NO_ASSERT_CHECK='TRUE';
      NO_DIR_CHECK='TRUE';
      ALLOW_CONNECT='TRUE';
    'VCCINT_2':
      PIN_NUMBER='(0,0,0,0,H8)';
      PINUSE='POWER';
      NO_LOAD_CHECK='Both';
      NO_IO_CHECK='Both';
      NO_ASSERT_CHECK='TRUE';
      NO_DIR_CHECK='TRUE';
      ALLOW_CONNECT='TRUE';
    'VCCINT_3':
      PIN_NUMBER='(0,0,0,0,J7)';
      PINUSE='POWER';
      NO_LOAD_CHECK='Both';
      NO_IO_CHECK='Both';
      NO_ASSERT_CHECK='TRUE';
      NO_DIR_CHECK='TRUE';
      ALLOW_CONNECT='TRUE';
    'VCCINT_4':
      PIN_NUMBER='(0,0,0,0,J9)';
      PINUSE='POWER';
      NO_LOAD_CHECK='Both';
      NO_IO_CHECK='Both';
      NO_ASSERT_CHECK='TRUE';
      NO_DIR_CHECK='TRUE';
      ALLOW_CONNECT='TRUE';
    'VCCINT_5':
      PIN_NUMBER='(0,0,0,0,K8)';
      PINUSE='POWER';
      NO_LOAD_CHECK='Both';
      NO_IO_CHECK='Both';
      NO_ASSERT_CHECK='TRUE';
      NO_DIR_CHECK='TRUE';
      ALLOW_CONNECT='TRUE';
    'VCCINT_6':
      PIN_NUMBER='(0,0,0,0,L7)';
      PINUSE='POWER';
      NO_LOAD_CHECK='Both';
      NO_IO_CHECK='Both';
      NO_ASSERT_CHECK='TRUE';
      NO_DIR_CHECK='TRUE';
      ALLOW_CONNECT='TRUE';
    'VCCINT_7':
      PIN_NUMBER='(0,0,0,0,M8)';
      PINUSE='POWER';
      NO_LOAD_CHECK='Both';
      NO_IO_CHECK='Both';
      NO_ASSERT_CHECK='TRUE';
      NO_DIR_CHECK='TRUE';
      ALLOW_CONNECT='TRUE';
    'VCCINT_8':
      PIN_NUMBER='(0,0,0,0,N7)';
      PINUSE='POWER';
      NO_LOAD_CHECK='Both';
      NO_IO_CHECK='Both';
      NO_ASSERT_CHECK='TRUE';
      NO_DIR_CHECK='TRUE';
      ALLOW_CONNECT='TRUE';
    'VCCINT_9':
      PIN_NUMBER='(0,0,0,0,P10)';
      PINUSE='POWER';
      NO_LOAD_CHECK='Both';
      NO_IO_CHECK='Both';
      NO_ASSERT_CHECK='TRUE';
      NO_DIR_CHECK='TRUE';
      ALLOW_CONNECT='TRUE';
    'VCCINT_10':
      PIN_NUMBER='(0,0,0,0,P8)';
      PINUSE='POWER';
      NO_LOAD_CHECK='Both';
      NO_IO_CHECK='Both';
      NO_ASSERT_CHECK='TRUE';
      NO_DIR_CHECK='TRUE';
      ALLOW_CONNECT='TRUE';
    'VCCINT_11':
      PIN_NUMBER='(0,0,0,0,R7)';
      PINUSE='POWER';
      NO_LOAD_CHECK='Both';
      NO_IO_CHECK='Both';
      NO_ASSERT_CHECK='TRUE';
      NO_DIR_CHECK='TRUE';
      ALLOW_CONNECT='TRUE';
    'VCCINT_12':
      PIN_NUMBER='(0,0,0,0,R9)';
      PINUSE='POWER';
      NO_LOAD_CHECK='Both';
      NO_IO_CHECK='Both';
      NO_ASSERT_CHECK='TRUE';
      NO_DIR_CHECK='TRUE';
      ALLOW_CONNECT='TRUE';
    'VCCINT_13':
      PIN_NUMBER='(0,0,0,0,T10)';
      PINUSE='POWER';
      NO_LOAD_CHECK='Both';
      NO_IO_CHECK='Both';
      NO_ASSERT_CHECK='TRUE';
      NO_DIR_CHECK='TRUE';
      ALLOW_CONNECT='TRUE';
    'VCCINT_14':
      PIN_NUMBER='(0,0,0,0,T8)';
      PINUSE='POWER';
      NO_LOAD_CHECK='Both';
      NO_IO_CHECK='Both';
      NO_ASSERT_CHECK='TRUE';
      NO_DIR_CHECK='TRUE';
      ALLOW_CONNECT='TRUE';
    'VCCO_0_1':
      PIN_NUMBER='(0,0,0,0,F12)';
      PINUSE='POWER';
      NO_LOAD_CHECK='Both';
      NO_IO_CHECK='Both';
      NO_ASSERT_CHECK='TRUE';
      NO_DIR_CHECK='TRUE';
      ALLOW_CONNECT='TRUE';
    'VCCO_0_2':
      PIN_NUMBER='(0,0,0,0,T12)';
      PINUSE='POWER';
      NO_LOAD_CHECK='Both';
      NO_IO_CHECK='Both';
      NO_ASSERT_CHECK='TRUE';
      NO_DIR_CHECK='TRUE';
      ALLOW_CONNECT='TRUE';
    'VCCO_13_1':
      PIN_NUMBER='(0,0,0,0,AA17)';
      PINUSE='POWER';
      NO_LOAD_CHECK='Both';
      NO_IO_CHECK='Both';
      NO_ASSERT_CHECK='TRUE';
      NO_DIR_CHECK='TRUE';
      ALLOW_CONNECT='TRUE';
    'VCCO_13_2':
      PIN_NUMBER='(0,0,0,0,AB14)';
      PINUSE='POWER';
      NO_LOAD_CHECK='Both';
      NO_IO_CHECK='Both';
      NO_ASSERT_CHECK='TRUE';
      NO_DIR_CHECK='TRUE';
      ALLOW_CONNECT='TRUE';
    'VCCO_13_3':
      PIN_NUMBER='(0,0,0,0,V16)';
      PINUSE='POWER';
      NO_LOAD_CHECK='Both';
      NO_IO_CHECK='Both';
      NO_ASSERT_CHECK='TRUE';
      NO_DIR_CHECK='TRUE';
      ALLOW_CONNECT='TRUE';
    'VCCO_13_4':
      PIN_NUMBER='(0,0,0,0,W13)';
      PINUSE='POWER';
      NO_LOAD_CHECK='Both';
      NO_IO_CHECK='Both';
      NO_ASSERT_CHECK='TRUE';
      NO_DIR_CHECK='TRUE';
      ALLOW_CONNECT='TRUE';
    'VCCO_13_5':
      PIN_NUMBER='(0,0,0,0,Y10)';
      PINUSE='POWER';
      NO_LOAD_CHECK='Both';
      NO_IO_CHECK='Both';
      NO_ASSERT_CHECK='TRUE';
      NO_DIR_CHECK='TRUE';
      ALLOW_CONNECT='TRUE';
    'VCCO_14_1':
      PIN_NUMBER='(0,0,0,0,M14)';
      PINUSE='POWER';
      NO_LOAD_CHECK='Both';
      NO_IO_CHECK='Both';
      NO_ASSERT_CHECK='TRUE';
      NO_DIR_CHECK='TRUE';
      ALLOW_CONNECT='TRUE';
    'VCCO_14_2':
      PIN_NUMBER='(0,0,0,0,P18)';
      PINUSE='POWER';
      NO_LOAD_CHECK='Both';
      NO_IO_CHECK='Both';
      NO_ASSERT_CHECK='TRUE';
      NO_DIR_CHECK='TRUE';
      ALLOW_CONNECT='TRUE';
    'VCCO_14_3':
      PIN_NUMBER='(0,0,0,0,R15)';
      PINUSE='POWER';
      NO_LOAD_CHECK='Both';
      NO_IO_CHECK='Both';
      NO_ASSERT_CHECK='TRUE';
      NO_DIR_CHECK='TRUE';
      ALLOW_CONNECT='TRUE';
    'VCCO_14_4':
      PIN_NUMBER='(0,0,0,0,T22)';
      PINUSE='POWER';
      NO_LOAD_CHECK='Both';
      NO_IO_CHECK='Both';
      NO_ASSERT_CHECK='TRUE';
      NO_DIR_CHECK='TRUE';
      ALLOW_CONNECT='TRUE';
    'VCCO_14_5':
      PIN_NUMBER='(0,0,0,0,U19)';
      PINUSE='POWER';
      NO_LOAD_CHECK='Both';
      NO_IO_CHECK='Both';
      NO_ASSERT_CHECK='TRUE';
      NO_DIR_CHECK='TRUE';
      ALLOW_CONNECT='TRUE';
    'VCCO_14_6':
      PIN_NUMBER='(0,0,0,0,Y20)';
      PINUSE='POWER';
      NO_LOAD_CHECK='Both';
      NO_IO_CHECK='Both';
      NO_ASSERT_CHECK='TRUE';
      NO_DIR_CHECK='TRUE';
      ALLOW_CONNECT='TRUE';
    'VCCO_15_1':
      PIN_NUMBER='(0,0,0,0,G19)';
      PINUSE='POWER';
      NO_LOAD_CHECK='Both';
      NO_IO_CHECK='Both';
      NO_ASSERT_CHECK='TRUE';
      NO_DIR_CHECK='TRUE';
      ALLOW_CONNECT='TRUE';
    'VCCO_15_2':
      PIN_NUMBER='(0,0,0,0,H16)';
      PINUSE='POWER';
      NO_LOAD_CHECK='Both';
      NO_IO_CHECK='Both';
      NO_ASSERT_CHECK='TRUE';
      NO_DIR_CHECK='TRUE';
      ALLOW_CONNECT='TRUE';
    'VCCO_15_3':
      PIN_NUMBER='(0,0,0,0,J13)';
      PINUSE='POWER';
      NO_LOAD_CHECK='Both';
      NO_IO_CHECK='Both';
      NO_ASSERT_CHECK='TRUE';
      NO_DIR_CHECK='TRUE';
      ALLOW_CONNECT='TRUE';
    'VCCO_15_4':
      PIN_NUMBER='(0,0,0,0,K20)';
      PINUSE='POWER';
      NO_LOAD_CHECK='Both';
      NO_IO_CHECK='Both';
      NO_ASSERT_CHECK='TRUE';
      NO_DIR_CHECK='TRUE';
      ALLOW_CONNECT='TRUE';
    'VCCO_15_5':
      PIN_NUMBER='(0,0,0,0,L17)';
      PINUSE='POWER';
      NO_LOAD_CHECK='Both';
      NO_IO_CHECK='Both';
      NO_ASSERT_CHECK='TRUE';
      NO_DIR_CHECK='TRUE';
      ALLOW_CONNECT='TRUE';
    'VCCO_15_6':
      PIN_NUMBER='(0,0,0,0,N21)';
      PINUSE='POWER';
      NO_LOAD_CHECK='Both';
      NO_IO_CHECK='Both';
      NO_ASSERT_CHECK='TRUE';
      NO_DIR_CHECK='TRUE';
      ALLOW_CONNECT='TRUE';
    'VCCO_16_1':
      PIN_NUMBER='(0,0,0,0,A17)';
      PINUSE='POWER';
      NO_LOAD_CHECK='Both';
      NO_IO_CHECK='Both';
      NO_ASSERT_CHECK='TRUE';
      NO_DIR_CHECK='TRUE';
      ALLOW_CONNECT='TRUE';
    'VCCO_16_2':
      PIN_NUMBER='(0,0,0,0,B14)';
      PINUSE='POWER';
      NO_LOAD_CHECK='Both';
      NO_IO_CHECK='Both';
      NO_ASSERT_CHECK='TRUE';
      NO_DIR_CHECK='TRUE';
      ALLOW_CONNECT='TRUE';
    'VCCO_16_3':
      PIN_NUMBER='(0,0,0,0,C21)';
      PINUSE='POWER';
      NO_LOAD_CHECK='Both';
      NO_IO_CHECK='Both';
      NO_ASSERT_CHECK='TRUE';
      NO_DIR_CHECK='TRUE';
      ALLOW_CONNECT='TRUE';
    'VCCO_16_4':
      PIN_NUMBER='(0,0,0,0,D18)';
      PINUSE='POWER';
      NO_LOAD_CHECK='Both';
      NO_IO_CHECK='Both';
      NO_ASSERT_CHECK='TRUE';
      NO_DIR_CHECK='TRUE';
      ALLOW_CONNECT='TRUE';
    'VCCO_16_5':
      PIN_NUMBER='(0,0,0,0,E15)';
      PINUSE='POWER';
      NO_LOAD_CHECK='Both';
      NO_IO_CHECK='Both';
      NO_ASSERT_CHECK='TRUE';
      NO_DIR_CHECK='TRUE';
      ALLOW_CONNECT='TRUE';
    'VCCO_16_6':
      PIN_NUMBER='(0,0,0,0,F22)';
      PINUSE='POWER';
      NO_LOAD_CHECK='Both';
      NO_IO_CHECK='Both';
      NO_ASSERT_CHECK='TRUE';
      NO_DIR_CHECK='TRUE';
      ALLOW_CONNECT='TRUE';
    'VCCO_34_1':
      PIN_NUMBER='(0,0,0,0,AA7)';
      PINUSE='POWER';
      NO_LOAD_CHECK='Both';
      NO_IO_CHECK='Both';
      NO_ASSERT_CHECK='TRUE';
      NO_DIR_CHECK='TRUE';
      ALLOW_CONNECT='TRUE';
    'VCCO_34_2':
      PIN_NUMBER='(0,0,0,0,AB4)';
      PINUSE='POWER';
      NO_LOAD_CHECK='Both';
      NO_IO_CHECK='Both';
      NO_ASSERT_CHECK='TRUE';
      NO_DIR_CHECK='TRUE';
      ALLOW_CONNECT='TRUE';
    'VCCO_34_3':
      PIN_NUMBER='(0,0,0,0,R5)';
      PINUSE='POWER';
      NO_LOAD_CHECK='Both';
      NO_IO_CHECK='Both';
      NO_ASSERT_CHECK='TRUE';
      NO_DIR_CHECK='TRUE';
      ALLOW_CONNECT='TRUE';
    'VCCO_34_4':
      PIN_NUMBER='(0,0,0,0,T2)';
      PINUSE='POWER';
      NO_LOAD_CHECK='Both';
      NO_IO_CHECK='Both';
      NO_ASSERT_CHECK='TRUE';
      NO_DIR_CHECK='TRUE';
      ALLOW_CONNECT='TRUE';
    'VCCO_34_5':
      PIN_NUMBER='(0,0,0,0,V6)';
      PINUSE='POWER';
      NO_LOAD_CHECK='Both';
      NO_IO_CHECK='Both';
      NO_ASSERT_CHECK='TRUE';
      NO_DIR_CHECK='TRUE';
      ALLOW_CONNECT='TRUE';
    'VCCO_34_6':
      PIN_NUMBER='(0,0,0,0,W3)';
      PINUSE='POWER';
      NO_LOAD_CHECK='Both';
      NO_IO_CHECK='Both';
      NO_ASSERT_CHECK='TRUE';
      NO_DIR_CHECK='TRUE';
      ALLOW_CONNECT='TRUE';
    'VCCO_35_1':
      PIN_NUMBER='(0,0,0,0,C1)';
      PINUSE='POWER';
      NO_LOAD_CHECK='Both';
      NO_IO_CHECK='Both';
      NO_ASSERT_CHECK='TRUE';
      NO_DIR_CHECK='TRUE';
      ALLOW_CONNECT='TRUE';
    'VCCO_35_2':
      PIN_NUMBER='(0,0,0,0,F2)';
      PINUSE='POWER';
      NO_LOAD_CHECK='Both';
      NO_IO_CHECK='Both';
      NO_ASSERT_CHECK='TRUE';
      NO_DIR_CHECK='TRUE';
      ALLOW_CONNECT='TRUE';
    'VCCO_35_3':
      PIN_NUMBER='(0,0,0,0,H6)';
      PINUSE='POWER';
      NO_LOAD_CHECK='Both';
      NO_IO_CHECK='Both';
      NO_ASSERT_CHECK='TRUE';
      NO_DIR_CHECK='TRUE';
      ALLOW_CONNECT='TRUE';
    'VCCO_35_4':
      PIN_NUMBER='(0,0,0,0,J3)';
      PINUSE='POWER';
      NO_LOAD_CHECK='Both';
      NO_IO_CHECK='Both';
      NO_ASSERT_CHECK='TRUE';
      NO_DIR_CHECK='TRUE';
      ALLOW_CONNECT='TRUE';
    'VCCO_35_5':
      PIN_NUMBER='(0,0,0,0,M4)';
      PINUSE='POWER';
      NO_LOAD_CHECK='Both';
      NO_IO_CHECK='Both';
      NO_ASSERT_CHECK='TRUE';
      NO_DIR_CHECK='TRUE';
      ALLOW_CONNECT='TRUE';
    'VCCO_35_6':
      PIN_NUMBER='(0,0,0,0,N1)';
      PINUSE='POWER';
      NO_LOAD_CHECK='Both';
      NO_IO_CHECK='Both';
      NO_ASSERT_CHECK='TRUE';
      NO_DIR_CHECK='TRUE';
      ALLOW_CONNECT='TRUE';
  end_pin;
  body
      PART_NAME='XC7A200T_2FBG484C_FBG484';
      BODY_NAME='XC7A200T_2FBG484C_FBG484';
      PHYS_DES_PREFIX='U';
      CLASS='IC';
      JEDEC_TYPE='BGA484_906_P0394_V3';
      ALT_SYMBOLS='(BGA484_906_P0394_V3)';
      DESCRIPTION='IC,FPGA,ARTIX-7,XC7A100T-1FGG484I,FGG484';
      CPN_STATUS='';
      PARENT_PART_TYPE='XC7A200T_2FBG484C_FBG484';
      PARENT_PPT='XC7A200T_2FBG484C_FBG484';
      PARENT_PPT_PART='XC7A200T_2FBG484C_FBG484-G240-10069-01';
  end_body;
end_primitive;
primitive 'XTAL_2-G131-10075-01';
  pin
    '1':
      PIN_NUMBER='(1)';
      PINUSE='UNSPEC';
      NO_LOAD_CHECK='Both';
      NO_IO_CHECK='Both';
      NO_ASSERT_CHECK='TRUE';
      NO_DIR_CHECK='TRUE';
      ALLOW_CONNECT='TRUE';
    '2':
      PIN_NUMBER='(2)';
      PINUSE='UNSPEC';
      NO_LOAD_CHECK='Both';
      NO_IO_CHECK='Both';
      NO_ASSERT_CHECK='TRUE';
      NO_DIR_CHECK='TRUE';
      ALLOW_CONNECT='TRUE';
  end_pin;
  body
      PART_NAME='XTAL_2';
      BODY_NAME='XTAL_2';
      PHYS_DES_PREFIX='Y';
      CLASS='DISCRETE';
      JEDEC_TYPE='SMC_Y2_079X047';
      ALT_SYMBOLS='(SMC_Y2_079X047)';
      DESCRIPTION='XTAL,32.768KHZ,12.5PF,20PPM,2.0X1.2X0.6MM';
      CPN_STATUS='';
      PARENT_PART_TYPE='XTAL_2';
      PARENT_PPT='XTAL_2';
      PARENT_PPT_PART='XTAL_2-G131-10075-01';
  end_body;
end_primitive;
primitive 'XTAL_4-G131-10038-02';
  pin
    '1':
      PIN_NUMBER='(1)';
      PINUSE='UNSPEC';
      NO_LOAD_CHECK='Both';
      NO_IO_CHECK='Both';
      NO_ASSERT_CHECK='TRUE';
      NO_DIR_CHECK='TRUE';
      ALLOW_CONNECT='TRUE';
    '2':
      PIN_NUMBER='(2)';
      PINUSE='UNSPEC';
      NO_LOAD_CHECK='Both';
      NO_IO_CHECK='Both';
      NO_ASSERT_CHECK='TRUE';
      NO_DIR_CHECK='TRUE';
      ALLOW_CONNECT='TRUE';
    '3':
      PIN_NUMBER='(3)';
      PINUSE='UNSPEC';
      NO_LOAD_CHECK='Both';
      NO_IO_CHECK='Both';
      NO_ASSERT_CHECK='TRUE';
      NO_DIR_CHECK='TRUE';
      ALLOW_CONNECT='TRUE';
    '4':
      PIN_NUMBER='(4)';
      PINUSE='UNSPEC';
      NO_LOAD_CHECK='Both';
      NO_IO_CHECK='Both';
      NO_ASSERT_CHECK='TRUE';
      NO_DIR_CHECK='TRUE';
      ALLOW_CONNECT='TRUE';
  end_pin;
  body
      PART_NAME='XTAL_4';
      BODY_NAME='XTAL_4';
      PHYS_DES_PREFIX='Y';
      CLASS='DISCRETE';
      JEDEC_TYPE='SMC_Y4_126X098_V5_H032';
      ALT_SYMBOLS='(SMC_Y4_126X098_V5_H032)';
      DESCRIPTION='XTAL,12MHZ,18PF,20PPM,3.2MMX2.5MMX0.8MM,SMT';
      CPN_STATUS='';
      PARENT_PART_TYPE='XTAL_4';
      PARENT_PPT='XTAL_4';
      PARENT_PPT_PART='XTAL_4-G131-10038-02';
  end_body;
end_primitive;
END.
